G04*
G04 #@! TF.GenerationSoftware,Altium Limited,Altium Designer,23.6.0 (18)*
G04*
G04 Layer_Color=65535*
%FSLAX44Y44*%
%MOMM*%
G71*
G04*
G04 #@! TF.SameCoordinates,0D6CC9A4-690D-4EF8-AA6E-9FB67146BD04*
G04*
G04*
G04 #@! TF.FilePolarity,Positive*
G04*
G01*
G75*
%ADD10C,0.2500*%
%ADD11C,0.4500*%
%ADD12C,0.5000*%
%ADD13C,0.2000*%
%ADD14C,0.1000*%
%ADD15C,0.1270*%
G36*
X387648Y174831D02*
X387772Y174817D01*
X387925Y174803D01*
X388078Y174790D01*
X388258Y174748D01*
X388632Y174665D01*
X389048Y174540D01*
X389256Y174457D01*
X389450Y174360D01*
X389645Y174235D01*
X389839Y174110D01*
X389853Y174096D01*
X389880Y174082D01*
X389936Y174041D01*
X390005Y173971D01*
X390075Y173902D01*
X390172Y173805D01*
X390269Y173694D01*
X390380Y173583D01*
X390491Y173444D01*
X390602Y173278D01*
X390726Y173111D01*
X390837Y172931D01*
X390934Y172723D01*
X391045Y172515D01*
X391129Y172293D01*
X391212Y172043D01*
X389964Y171752D01*
Y171766D01*
X389950Y171794D01*
X389922Y171849D01*
X389894Y171919D01*
X389867Y172002D01*
X389825Y172113D01*
X389714Y172335D01*
X389575Y172584D01*
X389409Y172834D01*
X389201Y173070D01*
X388979Y173278D01*
X388951Y173306D01*
X388868Y173361D01*
X388729Y173430D01*
X388549Y173528D01*
X388313Y173611D01*
X388050Y173694D01*
X387731Y173749D01*
X387384Y173763D01*
X387273D01*
X387204Y173749D01*
X387107D01*
X386996Y173736D01*
X386732Y173694D01*
X386441Y173638D01*
X386136Y173541D01*
X385817Y173403D01*
X385526Y173222D01*
X385512D01*
X385498Y173195D01*
X385401Y173125D01*
X385276Y173014D01*
X385124Y172848D01*
X384943Y172640D01*
X384777Y172404D01*
X384624Y172113D01*
X384486Y171794D01*
Y171780D01*
X384472Y171752D01*
X384458Y171711D01*
X384444Y171641D01*
X384416Y171558D01*
X384389Y171461D01*
X384347Y171225D01*
X384291Y170948D01*
X384236Y170643D01*
X384208Y170310D01*
X384194Y169949D01*
Y169936D01*
Y169894D01*
Y169825D01*
Y169741D01*
X384208Y169644D01*
Y169520D01*
X384222Y169381D01*
X384236Y169228D01*
X384278Y168895D01*
X384347Y168535D01*
X384430Y168174D01*
X384541Y167814D01*
Y167800D01*
X384555Y167772D01*
X384583Y167731D01*
X384610Y167661D01*
X384694Y167495D01*
X384818Y167301D01*
X384971Y167079D01*
X385165Y166843D01*
X385387Y166635D01*
X385651Y166441D01*
X385664D01*
X385692Y166427D01*
X385734Y166399D01*
X385789Y166371D01*
X385859Y166344D01*
X385942Y166302D01*
X386136Y166219D01*
X386386Y166136D01*
X386663Y166066D01*
X386968Y166011D01*
X387287Y165997D01*
X387384D01*
X387467Y166011D01*
X387564D01*
X387662Y166025D01*
X387911Y166080D01*
X388202Y166150D01*
X388494Y166260D01*
X388799Y166413D01*
X388951Y166496D01*
X389090Y166607D01*
X389104Y166621D01*
X389118Y166635D01*
X389159Y166677D01*
X389215Y166718D01*
X389270Y166787D01*
X389340Y166871D01*
X389423Y166954D01*
X389492Y167065D01*
X389575Y167190D01*
X389672Y167328D01*
X389756Y167467D01*
X389839Y167633D01*
X389908Y167814D01*
X389977Y168008D01*
X390047Y168216D01*
X390102Y168438D01*
X391378Y168119D01*
Y168105D01*
X391364Y168049D01*
X391337Y167966D01*
X391295Y167855D01*
X391253Y167731D01*
X391198Y167578D01*
X391129Y167411D01*
X391045Y167231D01*
X390851Y166843D01*
X390602Y166455D01*
X390449Y166260D01*
X390297Y166066D01*
X390130Y165900D01*
X389936Y165733D01*
X389922Y165720D01*
X389894Y165692D01*
X389825Y165664D01*
X389756Y165609D01*
X389645Y165539D01*
X389534Y165470D01*
X389381Y165401D01*
X389229Y165331D01*
X389048Y165248D01*
X388854Y165179D01*
X388646Y165109D01*
X388424Y165040D01*
X388189Y164984D01*
X387939Y164957D01*
X387675Y164929D01*
X387398Y164915D01*
X387245D01*
X387135Y164929D01*
X387010D01*
X386857Y164943D01*
X386691Y164971D01*
X386497Y164998D01*
X386094Y165068D01*
X385678Y165179D01*
X385262Y165331D01*
X385068Y165428D01*
X384874Y165539D01*
X384860Y165553D01*
X384832Y165567D01*
X384777Y165609D01*
X384721Y165664D01*
X384638Y165720D01*
X384541Y165803D01*
X384430Y165900D01*
X384319Y166011D01*
X384208Y166136D01*
X384084Y166260D01*
X383834Y166579D01*
X383598Y166954D01*
X383390Y167370D01*
Y167384D01*
X383362Y167425D01*
X383348Y167495D01*
X383307Y167578D01*
X383279Y167689D01*
X383237Y167828D01*
X383182Y167980D01*
X383140Y168146D01*
X383099Y168327D01*
X383043Y168535D01*
X382974Y168965D01*
X382919Y169450D01*
X382891Y169949D01*
Y169963D01*
Y170019D01*
Y170102D01*
X382905Y170199D01*
Y170338D01*
X382919Y170476D01*
X382932Y170657D01*
X382960Y170837D01*
X383030Y171239D01*
X383126Y171683D01*
X383265Y172127D01*
X383459Y172557D01*
X383473Y172570D01*
X383487Y172612D01*
X383515Y172668D01*
X383570Y172737D01*
X383626Y172834D01*
X383695Y172945D01*
X383875Y173195D01*
X384111Y173472D01*
X384389Y173749D01*
X384707Y174027D01*
X385082Y174263D01*
X385096Y174276D01*
X385137Y174290D01*
X385193Y174318D01*
X385262Y174360D01*
X385373Y174401D01*
X385484Y174443D01*
X385623Y174498D01*
X385775Y174554D01*
X385942Y174609D01*
X386122Y174665D01*
X386510Y174748D01*
X386954Y174817D01*
X387412Y174845D01*
X387551D01*
X387648Y174831D01*
D02*
G37*
G36*
X295950Y174831D02*
X296075Y174817D01*
X296227Y174803D01*
X296380Y174790D01*
X296560Y174748D01*
X296934Y174665D01*
X297351Y174540D01*
X297558Y174457D01*
X297753Y174359D01*
X297947Y174235D01*
X298141Y174110D01*
X298155Y174096D01*
X298183Y174082D01*
X298238Y174041D01*
X298307Y173971D01*
X298377Y173902D01*
X298474Y173805D01*
X298571Y173694D01*
X298682Y173583D01*
X298793Y173444D01*
X298904Y173278D01*
X299029Y173111D01*
X299139Y172931D01*
X299237Y172723D01*
X299347Y172515D01*
X299431Y172293D01*
X299514Y172043D01*
X298266Y171752D01*
Y171766D01*
X298252Y171794D01*
X298224Y171849D01*
X298197Y171919D01*
X298169Y172002D01*
X298127Y172113D01*
X298016Y172335D01*
X297878Y172584D01*
X297711Y172834D01*
X297503Y173070D01*
X297281Y173278D01*
X297253Y173305D01*
X297170Y173361D01*
X297031Y173430D01*
X296851Y173527D01*
X296616Y173611D01*
X296352Y173694D01*
X296033Y173749D01*
X295686Y173763D01*
X295575D01*
X295506Y173749D01*
X295409D01*
X295298Y173736D01*
X295035Y173694D01*
X294743Y173638D01*
X294438Y173541D01*
X294119Y173403D01*
X293828Y173222D01*
X293814D01*
X293800Y173195D01*
X293703Y173125D01*
X293578Y173014D01*
X293426Y172848D01*
X293245Y172640D01*
X293079Y172404D01*
X292927Y172113D01*
X292788Y171794D01*
Y171780D01*
X292774Y171752D01*
X292760Y171711D01*
X292746Y171641D01*
X292718Y171558D01*
X292691Y171461D01*
X292649Y171225D01*
X292594Y170948D01*
X292538Y170643D01*
X292510Y170310D01*
X292496Y169949D01*
Y169935D01*
Y169894D01*
Y169825D01*
Y169741D01*
X292510Y169644D01*
Y169520D01*
X292524Y169381D01*
X292538Y169228D01*
X292580Y168895D01*
X292649Y168535D01*
X292732Y168174D01*
X292843Y167814D01*
Y167800D01*
X292857Y167772D01*
X292885Y167730D01*
X292913Y167661D01*
X292996Y167495D01*
X293121Y167300D01*
X293273Y167079D01*
X293467Y166843D01*
X293689Y166635D01*
X293953Y166441D01*
X293967D01*
X293994Y166427D01*
X294036Y166399D01*
X294091Y166371D01*
X294161Y166344D01*
X294244Y166302D01*
X294438Y166219D01*
X294688Y166136D01*
X294965Y166066D01*
X295270Y166011D01*
X295589Y165997D01*
X295686D01*
X295770Y166011D01*
X295867D01*
X295964Y166025D01*
X296213Y166080D01*
X296504Y166150D01*
X296796Y166260D01*
X297101Y166413D01*
X297253Y166496D01*
X297392Y166607D01*
X297406Y166621D01*
X297420Y166635D01*
X297461Y166677D01*
X297517Y166718D01*
X297572Y166787D01*
X297642Y166871D01*
X297725Y166954D01*
X297794Y167065D01*
X297878Y167190D01*
X297975Y167328D01*
X298058Y167467D01*
X298141Y167633D01*
X298210Y167814D01*
X298280Y168008D01*
X298349Y168216D01*
X298405Y168438D01*
X299680Y168119D01*
Y168105D01*
X299667Y168049D01*
X299639Y167966D01*
X299597Y167855D01*
X299556Y167730D01*
X299500Y167578D01*
X299431Y167411D01*
X299347Y167231D01*
X299153Y166843D01*
X298904Y166455D01*
X298751Y166260D01*
X298599Y166066D01*
X298432Y165900D01*
X298238Y165733D01*
X298224Y165720D01*
X298197Y165692D01*
X298127Y165664D01*
X298058Y165609D01*
X297947Y165539D01*
X297836Y165470D01*
X297683Y165401D01*
X297531Y165331D01*
X297351Y165248D01*
X297156Y165179D01*
X296948Y165109D01*
X296726Y165040D01*
X296491Y164984D01*
X296241Y164957D01*
X295977Y164929D01*
X295700Y164915D01*
X295548D01*
X295437Y164929D01*
X295312D01*
X295159Y164943D01*
X294993Y164971D01*
X294799Y164998D01*
X294396Y165068D01*
X293981Y165179D01*
X293564Y165331D01*
X293370Y165428D01*
X293176Y165539D01*
X293162Y165553D01*
X293134Y165567D01*
X293079Y165609D01*
X293023Y165664D01*
X292940Y165720D01*
X292843Y165803D01*
X292732Y165900D01*
X292621Y166011D01*
X292510Y166136D01*
X292386Y166260D01*
X292136Y166579D01*
X291900Y166954D01*
X291692Y167370D01*
Y167384D01*
X291664Y167425D01*
X291651Y167495D01*
X291609Y167578D01*
X291581Y167689D01*
X291540Y167827D01*
X291484Y167980D01*
X291443Y168146D01*
X291401Y168327D01*
X291346Y168535D01*
X291276Y168965D01*
X291221Y169450D01*
X291193Y169949D01*
Y169963D01*
Y170019D01*
Y170102D01*
X291207Y170199D01*
Y170338D01*
X291221Y170476D01*
X291234Y170657D01*
X291262Y170837D01*
X291332Y171239D01*
X291429Y171683D01*
X291567Y172127D01*
X291761Y172557D01*
X291775Y172570D01*
X291789Y172612D01*
X291817Y172668D01*
X291873Y172737D01*
X291928Y172834D01*
X291997Y172945D01*
X292178Y173195D01*
X292413Y173472D01*
X292691Y173749D01*
X293010Y174027D01*
X293384Y174263D01*
X293398Y174276D01*
X293440Y174290D01*
X293495Y174318D01*
X293564Y174359D01*
X293675Y174401D01*
X293786Y174443D01*
X293925Y174498D01*
X294077Y174554D01*
X294244Y174609D01*
X294424Y174665D01*
X294813Y174748D01*
X295256Y174817D01*
X295714Y174845D01*
X295853D01*
X295950Y174831D01*
D02*
G37*
G36*
X410309Y165082D02*
X409213D01*
Y165955D01*
X409199Y165942D01*
X409185Y165914D01*
X409144Y165858D01*
X409088Y165789D01*
X409019Y165720D01*
X408936Y165636D01*
X408839Y165539D01*
X408714Y165442D01*
X408589Y165345D01*
X408450Y165248D01*
X408284Y165165D01*
X408103Y165096D01*
X407923Y165026D01*
X407715Y164971D01*
X407493Y164943D01*
X407258Y164929D01*
X407174D01*
X407119Y164943D01*
X406952Y164957D01*
X406758Y164984D01*
X406522Y165040D01*
X406259Y165123D01*
X405995Y165234D01*
X405732Y165387D01*
X405718D01*
X405704Y165415D01*
X405621Y165470D01*
X405496Y165581D01*
X405344Y165720D01*
X405163Y165900D01*
X404983Y166122D01*
X404803Y166371D01*
X404650Y166663D01*
Y166677D01*
X404636Y166704D01*
X404623Y166746D01*
X404595Y166801D01*
X404567Y166884D01*
X404525Y166982D01*
X404498Y167079D01*
X404470Y167204D01*
X404401Y167481D01*
X404331Y167800D01*
X404290Y168160D01*
X404276Y168549D01*
Y168563D01*
Y168590D01*
Y168646D01*
Y168729D01*
X404290Y168812D01*
Y168923D01*
X404318Y169173D01*
X404359Y169464D01*
X404428Y169783D01*
X404512Y170116D01*
X404623Y170435D01*
Y170449D01*
X404636Y170476D01*
X404664Y170518D01*
X404692Y170574D01*
X404775Y170726D01*
X404886Y170920D01*
X405025Y171128D01*
X405205Y171336D01*
X405413Y171558D01*
X405663Y171738D01*
X405677D01*
X405690Y171752D01*
X405732Y171780D01*
X405788Y171808D01*
X405926Y171877D01*
X406120Y171974D01*
X406342Y172057D01*
X406606Y172127D01*
X406897Y172182D01*
X407202Y172196D01*
X407313D01*
X407424Y172182D01*
X407576Y172168D01*
X407757Y172127D01*
X407951Y172085D01*
X408145Y172016D01*
X408325Y171919D01*
X408353Y171905D01*
X408409Y171877D01*
X408492Y171808D01*
X408603Y171738D01*
X408741Y171641D01*
X408866Y171516D01*
X409005Y171392D01*
X409130Y171239D01*
Y174678D01*
X410309D01*
Y165082D01*
D02*
G37*
G36*
X305464Y170116D02*
X309055Y165082D01*
X307488D01*
X305061Y168493D01*
X305047Y168507D01*
X305020Y168549D01*
X304992Y168604D01*
X304937Y168673D01*
X304812Y168868D01*
X304673Y169076D01*
X304659Y169062D01*
X304618Y169006D01*
X304562Y168923D01*
X304493Y168812D01*
X304340Y168590D01*
X304271Y168493D01*
X304215Y168410D01*
X301788Y165082D01*
X300263D01*
X303966Y170047D01*
X300693Y174678D01*
X302204D01*
X303952Y172210D01*
Y172196D01*
X303980Y172182D01*
X304007Y172141D01*
X304049Y172085D01*
X304132Y171946D01*
X304257Y171780D01*
X304382Y171586D01*
X304507Y171392D01*
X304618Y171211D01*
X304715Y171045D01*
X304729Y171073D01*
X304770Y171128D01*
X304839Y171239D01*
X304937Y171378D01*
X305047Y171530D01*
X305186Y171724D01*
X305325Y171919D01*
X305491Y172127D01*
X307405Y174678D01*
X308792D01*
X305464Y170116D01*
D02*
G37*
G36*
X403028Y172182D02*
X403180Y172155D01*
X403360Y172099D01*
X403555Y172030D01*
X403777Y171933D01*
X404012Y171808D01*
X403582Y170726D01*
X403569Y170740D01*
X403513Y170768D01*
X403430Y170809D01*
X403319Y170851D01*
X403194Y170893D01*
X403042Y170934D01*
X402889Y170962D01*
X402737Y170976D01*
X402667D01*
X402598Y170962D01*
X402501Y170948D01*
X402404Y170920D01*
X402279Y170879D01*
X402154Y170823D01*
X402043Y170740D01*
X402029Y170726D01*
X401988Y170698D01*
X401946Y170643D01*
X401877Y170574D01*
X401807Y170476D01*
X401738Y170366D01*
X401669Y170241D01*
X401613Y170088D01*
X401599Y170060D01*
X401585Y169977D01*
X401558Y169852D01*
X401516Y169686D01*
X401474Y169478D01*
X401447Y169242D01*
X401433Y168993D01*
X401419Y168715D01*
Y165082D01*
X400240D01*
Y172043D01*
X401308D01*
Y170989D01*
X401322Y171003D01*
X401377Y171101D01*
X401447Y171225D01*
X401558Y171378D01*
X401669Y171530D01*
X401793Y171697D01*
X401918Y171835D01*
X402043Y171947D01*
X402057Y171960D01*
X402099Y171988D01*
X402182Y172030D01*
X402265Y172071D01*
X402376Y172113D01*
X402515Y172155D01*
X402653Y172182D01*
X402806Y172196D01*
X402903D01*
X403028Y172182D01*
D02*
G37*
G36*
X377690D02*
X377843Y172155D01*
X378023Y172099D01*
X378217Y172030D01*
X378439Y171933D01*
X378675Y171808D01*
X378245Y170726D01*
X378231Y170740D01*
X378176Y170768D01*
X378092Y170809D01*
X377981Y170851D01*
X377856Y170893D01*
X377704Y170934D01*
X377551Y170962D01*
X377399Y170976D01*
X377329D01*
X377260Y170962D01*
X377163Y170948D01*
X377066Y170920D01*
X376941Y170879D01*
X376816Y170823D01*
X376706Y170740D01*
X376692Y170726D01*
X376650Y170698D01*
X376608Y170643D01*
X376539Y170574D01*
X376470Y170476D01*
X376400Y170366D01*
X376331Y170241D01*
X376275Y170088D01*
X376262Y170060D01*
X376248Y169977D01*
X376220Y169852D01*
X376179Y169686D01*
X376137Y169478D01*
X376109Y169242D01*
X376095Y168993D01*
X376081Y168715D01*
Y165082D01*
X374903D01*
Y172043D01*
X375970D01*
Y170989D01*
X375984Y171003D01*
X376040Y171101D01*
X376109Y171225D01*
X376220Y171378D01*
X376331Y171530D01*
X376456Y171697D01*
X376581Y171835D01*
X376706Y171947D01*
X376719Y171960D01*
X376761Y171988D01*
X376844Y172030D01*
X376927Y172071D01*
X377038Y172113D01*
X377177Y172155D01*
X377316Y172182D01*
X377468Y172196D01*
X377565D01*
X377690Y172182D01*
D02*
G37*
G36*
X346958Y165082D02*
X345904D01*
Y166094D01*
X345890Y166080D01*
X345862Y166038D01*
X345821Y165983D01*
X345751Y165914D01*
X345668Y165830D01*
X345571Y165720D01*
X345460Y165623D01*
X345321Y165511D01*
X345169Y165401D01*
X345002Y165303D01*
X344822Y165206D01*
X344628Y165109D01*
X344406Y165040D01*
X344184Y164984D01*
X343934Y164943D01*
X343685Y164929D01*
X343588D01*
X343463Y164943D01*
X343310Y164957D01*
X343130Y164984D01*
X342936Y165026D01*
X342742Y165082D01*
X342534Y165165D01*
X342506Y165179D01*
X342450Y165206D01*
X342353Y165262D01*
X342243Y165331D01*
X342104Y165414D01*
X341979Y165511D01*
X341854Y165623D01*
X341743Y165747D01*
X341729Y165761D01*
X341702Y165817D01*
X341660Y165886D01*
X341604Y165997D01*
X341535Y166122D01*
X341480Y166274D01*
X341424Y166441D01*
X341383Y166621D01*
Y166635D01*
X341369Y166690D01*
X341355Y166773D01*
Y166884D01*
X341341Y167051D01*
X341327Y167231D01*
X341313Y167467D01*
Y167730D01*
Y172043D01*
X342492D01*
Y168174D01*
Y168160D01*
Y168133D01*
Y168091D01*
Y168022D01*
Y167869D01*
X342506Y167675D01*
Y167467D01*
X342520Y167259D01*
X342534Y167079D01*
X342561Y166926D01*
Y166912D01*
X342589Y166857D01*
X342617Y166773D01*
X342659Y166663D01*
X342728Y166552D01*
X342811Y166427D01*
X342908Y166316D01*
X343033Y166205D01*
X343047Y166191D01*
X343102Y166163D01*
X343172Y166122D01*
X343283Y166080D01*
X343407Y166025D01*
X343560Y165983D01*
X343726Y165955D01*
X343921Y165941D01*
X344018D01*
X344115Y165955D01*
X344240Y165969D01*
X344392Y166011D01*
X344558Y166052D01*
X344739Y166122D01*
X344919Y166205D01*
X344947Y166219D01*
X345002Y166260D01*
X345085Y166316D01*
X345183Y166399D01*
X345294Y166510D01*
X345405Y166635D01*
X345502Y166773D01*
X345585Y166940D01*
X345599Y166968D01*
X345612Y167023D01*
X345640Y167134D01*
X345682Y167287D01*
X345723Y167481D01*
X345751Y167717D01*
X345765Y167994D01*
X345779Y168313D01*
Y172043D01*
X346958D01*
Y165082D01*
D02*
G37*
G36*
X396038Y172182D02*
X396246Y172168D01*
X396482Y172141D01*
X396718Y172099D01*
X396953Y172043D01*
X397175Y171974D01*
X397203Y171960D01*
X397272Y171933D01*
X397369Y171891D01*
X397494Y171835D01*
X397633Y171752D01*
X397772Y171669D01*
X397896Y171558D01*
X398007Y171447D01*
X398021Y171433D01*
X398049Y171392D01*
X398091Y171322D01*
X398146Y171239D01*
X398215Y171114D01*
X398271Y170989D01*
X398326Y170837D01*
X398368Y170657D01*
Y170643D01*
X398382Y170601D01*
X398396Y170518D01*
X398410Y170407D01*
Y170254D01*
X398423Y170074D01*
X398437Y169839D01*
Y169575D01*
Y167994D01*
Y167980D01*
Y167925D01*
Y167841D01*
Y167731D01*
Y167606D01*
Y167453D01*
X398451Y167120D01*
Y166774D01*
X398465Y166427D01*
X398479Y166274D01*
Y166136D01*
X398493Y166011D01*
X398507Y165914D01*
Y165900D01*
X398521Y165844D01*
X398534Y165761D01*
X398576Y165650D01*
X398604Y165525D01*
X398659Y165387D01*
X398728Y165234D01*
X398798Y165082D01*
X397564D01*
X397550Y165096D01*
X397536Y165151D01*
X397508Y165220D01*
X397467Y165331D01*
X397425Y165456D01*
X397397Y165609D01*
X397369Y165775D01*
X397342Y165955D01*
X397328D01*
X397314Y165928D01*
X397231Y165858D01*
X397106Y165761D01*
X396940Y165636D01*
X396731Y165511D01*
X396523Y165373D01*
X396301Y165248D01*
X396066Y165151D01*
X396038Y165137D01*
X395955Y165123D01*
X395830Y165082D01*
X395677Y165040D01*
X395483Y164998D01*
X395261Y164971D01*
X395012Y164943D01*
X394762Y164929D01*
X394651D01*
X394568Y164943D01*
X394471D01*
X394360Y164957D01*
X394110Y164998D01*
X393833Y165068D01*
X393528Y165165D01*
X393251Y165303D01*
X393001Y165484D01*
X392973Y165511D01*
X392904Y165581D01*
X392807Y165706D01*
X392696Y165872D01*
X392585Y166080D01*
X392488Y166316D01*
X392418Y166607D01*
X392405Y166746D01*
X392391Y166912D01*
Y166940D01*
Y166995D01*
X392405Y167092D01*
X392418Y167217D01*
X392446Y167370D01*
X392488Y167522D01*
X392543Y167689D01*
X392612Y167841D01*
X392626Y167855D01*
X392654Y167911D01*
X392710Y167994D01*
X392779Y168091D01*
X392862Y168202D01*
X392973Y168313D01*
X393084Y168424D01*
X393223Y168521D01*
X393237Y168535D01*
X393292Y168563D01*
X393361Y168618D01*
X393472Y168673D01*
X393597Y168729D01*
X393750Y168798D01*
X393902Y168854D01*
X394083Y168909D01*
X394096D01*
X394152Y168923D01*
X394235Y168951D01*
X394346Y168965D01*
X394485Y168993D01*
X394665Y169020D01*
X394873Y169062D01*
X395123Y169090D01*
X395137D01*
X395192Y169103D01*
X395261D01*
X395359Y169117D01*
X395469Y169131D01*
X395608Y169159D01*
X395761Y169173D01*
X395927Y169200D01*
X396260Y169270D01*
X396620Y169339D01*
X396940Y169422D01*
X397092Y169464D01*
X397231Y169506D01*
Y169520D01*
Y169547D01*
X397245Y169630D01*
Y169727D01*
Y169783D01*
Y169811D01*
Y169825D01*
Y169839D01*
Y169922D01*
X397231Y170060D01*
X397203Y170213D01*
X397161Y170379D01*
X397092Y170546D01*
X397009Y170698D01*
X396898Y170823D01*
X396884Y170837D01*
X396815Y170893D01*
X396704Y170948D01*
X396565Y171031D01*
X396371Y171101D01*
X396149Y171170D01*
X395872Y171211D01*
X395553Y171225D01*
X395414D01*
X395275Y171211D01*
X395081Y171184D01*
X394887Y171156D01*
X394679Y171101D01*
X394485Y171031D01*
X394318Y170934D01*
X394305Y170920D01*
X394249Y170879D01*
X394180Y170809D01*
X394096Y170698D01*
X394013Y170560D01*
X393916Y170379D01*
X393833Y170157D01*
X393750Y169908D01*
X392599Y170060D01*
Y170074D01*
X392612Y170088D01*
Y170130D01*
X392626Y170185D01*
X392668Y170310D01*
X392724Y170490D01*
X392793Y170671D01*
X392876Y170865D01*
X392987Y171059D01*
X393112Y171239D01*
X393126Y171253D01*
X393181Y171308D01*
X393264Y171392D01*
X393375Y171503D01*
X393528Y171614D01*
X393708Y171725D01*
X393916Y171849D01*
X394152Y171947D01*
X394166D01*
X394180Y171960D01*
X394221Y171974D01*
X394277Y171988D01*
X394415Y172030D01*
X394610Y172071D01*
X394832Y172113D01*
X395109Y172155D01*
X395400Y172182D01*
X395733Y172196D01*
X395886D01*
X396038Y172182D01*
D02*
G37*
G36*
X357442Y171239D02*
X357456Y171253D01*
X357484Y171281D01*
X357525Y171322D01*
X357595Y171392D01*
X357664Y171461D01*
X357761Y171544D01*
X357886Y171628D01*
X358011Y171725D01*
X358150Y171808D01*
X358302Y171891D01*
X358663Y172043D01*
X358857Y172113D01*
X359065Y172155D01*
X359287Y172182D01*
X359509Y172196D01*
X359633D01*
X359786Y172182D01*
X359966Y172155D01*
X360174Y172127D01*
X360396Y172071D01*
X360618Y171988D01*
X360840Y171891D01*
X360868Y171877D01*
X360937Y171835D01*
X361034Y171766D01*
X361159Y171669D01*
X361284Y171544D01*
X361423Y171406D01*
X361547Y171239D01*
X361658Y171045D01*
X361672Y171017D01*
X361700Y170948D01*
X361741Y170823D01*
X361783Y170643D01*
X361825Y170421D01*
X361866Y170157D01*
X361894Y169839D01*
X361908Y169478D01*
Y165082D01*
X360729D01*
Y169492D01*
Y169506D01*
Y169533D01*
Y169575D01*
Y169630D01*
X360715Y169783D01*
X360687Y169977D01*
X360632Y170185D01*
X360563Y170393D01*
X360466Y170601D01*
X360341Y170768D01*
X360327Y170781D01*
X360271Y170837D01*
X360188Y170906D01*
X360063Y170976D01*
X359911Y171059D01*
X359730Y171114D01*
X359509Y171170D01*
X359259Y171184D01*
X359176D01*
X359079Y171170D01*
X358940Y171156D01*
X358801Y171114D01*
X358635Y171073D01*
X358469Y171003D01*
X358288Y170906D01*
X358274Y170893D01*
X358219Y170851D01*
X358136Y170795D01*
X358039Y170712D01*
X357928Y170601D01*
X357817Y170476D01*
X357720Y170324D01*
X357636Y170157D01*
X357623Y170130D01*
X357609Y170074D01*
X357581Y169963D01*
X357539Y169825D01*
X357498Y169644D01*
X357470Y169422D01*
X357456Y169173D01*
X357442Y168882D01*
Y165082D01*
X356263D01*
Y174678D01*
X357442D01*
Y171239D01*
D02*
G37*
G36*
X337125Y172182D02*
X337333Y172168D01*
X337569Y172141D01*
X337805Y172099D01*
X338040Y172043D01*
X338262Y171974D01*
X338290Y171960D01*
X338359Y171933D01*
X338456Y171891D01*
X338581Y171835D01*
X338720Y171752D01*
X338859Y171669D01*
X338983Y171558D01*
X339094Y171447D01*
X339108Y171433D01*
X339136Y171392D01*
X339178Y171322D01*
X339233Y171239D01*
X339302Y171114D01*
X339358Y170989D01*
X339413Y170837D01*
X339455Y170657D01*
Y170643D01*
X339469Y170601D01*
X339483Y170518D01*
X339497Y170407D01*
Y170254D01*
X339510Y170074D01*
X339524Y169838D01*
Y169575D01*
Y167994D01*
Y167980D01*
Y167925D01*
Y167841D01*
Y167730D01*
Y167606D01*
Y167453D01*
X339538Y167120D01*
Y166773D01*
X339552Y166427D01*
X339566Y166274D01*
Y166136D01*
X339580Y166011D01*
X339594Y165914D01*
Y165900D01*
X339608Y165844D01*
X339621Y165761D01*
X339663Y165650D01*
X339691Y165525D01*
X339746Y165387D01*
X339815Y165234D01*
X339885Y165082D01*
X338651D01*
X338637Y165096D01*
X338623Y165151D01*
X338595Y165220D01*
X338554Y165331D01*
X338512Y165456D01*
X338484Y165609D01*
X338456Y165775D01*
X338429Y165955D01*
X338415D01*
X338401Y165928D01*
X338318Y165858D01*
X338193Y165761D01*
X338027Y165636D01*
X337818Y165511D01*
X337611Y165373D01*
X337389Y165248D01*
X337153Y165151D01*
X337125Y165137D01*
X337042Y165123D01*
X336917Y165082D01*
X336764Y165040D01*
X336570Y164998D01*
X336348Y164971D01*
X336099Y164943D01*
X335849Y164929D01*
X335738D01*
X335655Y164943D01*
X335558D01*
X335447Y164957D01*
X335197Y164998D01*
X334920Y165068D01*
X334615Y165165D01*
X334338Y165303D01*
X334088Y165484D01*
X334060Y165511D01*
X333991Y165581D01*
X333894Y165706D01*
X333783Y165872D01*
X333672Y166080D01*
X333575Y166316D01*
X333505Y166607D01*
X333492Y166746D01*
X333478Y166912D01*
Y166940D01*
Y166995D01*
X333492Y167092D01*
X333505Y167217D01*
X333533Y167370D01*
X333575Y167522D01*
X333630Y167689D01*
X333700Y167841D01*
X333713Y167855D01*
X333741Y167911D01*
X333797Y167994D01*
X333866Y168091D01*
X333949Y168202D01*
X334060Y168313D01*
X334171Y168424D01*
X334310Y168521D01*
X334324Y168535D01*
X334379Y168563D01*
X334449Y168618D01*
X334559Y168673D01*
X334684Y168729D01*
X334837Y168798D01*
X334989Y168854D01*
X335170Y168909D01*
X335183D01*
X335239Y168923D01*
X335322Y168951D01*
X335433Y168965D01*
X335572Y168993D01*
X335752Y169020D01*
X335960Y169062D01*
X336210Y169090D01*
X336224D01*
X336279Y169103D01*
X336348D01*
X336446Y169117D01*
X336557Y169131D01*
X336695Y169159D01*
X336848Y169173D01*
X337014Y169200D01*
X337347Y169270D01*
X337707Y169339D01*
X338027Y169422D01*
X338179Y169464D01*
X338318Y169506D01*
Y169520D01*
Y169547D01*
X338332Y169630D01*
Y169727D01*
Y169783D01*
Y169811D01*
Y169825D01*
Y169838D01*
Y169922D01*
X338318Y170060D01*
X338290Y170213D01*
X338248Y170379D01*
X338179Y170546D01*
X338096Y170698D01*
X337985Y170823D01*
X337971Y170837D01*
X337902Y170892D01*
X337791Y170948D01*
X337652Y171031D01*
X337458Y171101D01*
X337236Y171170D01*
X336959Y171211D01*
X336640Y171225D01*
X336501D01*
X336362Y171211D01*
X336168Y171184D01*
X335974Y171156D01*
X335766Y171101D01*
X335572Y171031D01*
X335405Y170934D01*
X335392Y170920D01*
X335336Y170879D01*
X335267Y170809D01*
X335183Y170698D01*
X335100Y170560D01*
X335003Y170379D01*
X334920Y170157D01*
X334837Y169908D01*
X333686Y170060D01*
Y170074D01*
X333700Y170088D01*
Y170130D01*
X333713Y170185D01*
X333755Y170310D01*
X333811Y170490D01*
X333880Y170671D01*
X333963Y170865D01*
X334074Y171059D01*
X334199Y171239D01*
X334213Y171253D01*
X334268Y171308D01*
X334351Y171392D01*
X334462Y171503D01*
X334615Y171614D01*
X334795Y171724D01*
X335003Y171849D01*
X335239Y171946D01*
X335253D01*
X335267Y171960D01*
X335308Y171974D01*
X335364Y171988D01*
X335503Y172030D01*
X335697Y172071D01*
X335919Y172113D01*
X336196Y172155D01*
X336487Y172182D01*
X336820Y172196D01*
X336973D01*
X337125Y172182D01*
D02*
G37*
G36*
X328291Y174665D02*
X328568Y174651D01*
X328846Y174623D01*
X329123Y174581D01*
X329359Y174540D01*
X329373D01*
X329400Y174526D01*
X329442D01*
X329497Y174498D01*
X329650Y174457D01*
X329844Y174387D01*
X330066Y174290D01*
X330302Y174165D01*
X330538Y174027D01*
X330760Y173846D01*
X330773Y173832D01*
X330787Y173819D01*
X330829Y173777D01*
X330884Y173736D01*
X331023Y173597D01*
X331189Y173403D01*
X331370Y173167D01*
X331564Y172889D01*
X331744Y172570D01*
X331897Y172210D01*
Y172196D01*
X331911Y172168D01*
X331938Y172113D01*
X331952Y172030D01*
X331994Y171933D01*
X332021Y171822D01*
X332049Y171697D01*
X332091Y171544D01*
X332132Y171392D01*
X332160Y171211D01*
X332229Y170823D01*
X332271Y170393D01*
X332285Y169922D01*
Y169908D01*
Y169880D01*
Y169811D01*
Y169741D01*
X332271Y169644D01*
Y169533D01*
X332257Y169270D01*
X332216Y168965D01*
X332174Y168646D01*
X332105Y168313D01*
X332021Y167980D01*
Y167966D01*
X332008Y167938D01*
X331994Y167897D01*
X331980Y167841D01*
X331924Y167689D01*
X331841Y167495D01*
X331758Y167273D01*
X331647Y167051D01*
X331508Y166815D01*
X331370Y166593D01*
X331356Y166565D01*
X331300Y166496D01*
X331217Y166399D01*
X331106Y166274D01*
X330981Y166136D01*
X330829Y165997D01*
X330676Y165844D01*
X330496Y165720D01*
X330468Y165706D01*
X330413Y165664D01*
X330316Y165609D01*
X330177Y165539D01*
X330011Y165456D01*
X329816Y165387D01*
X329594Y165303D01*
X329345Y165234D01*
X329317D01*
X329276Y165220D01*
X329234Y165206D01*
X329095Y165193D01*
X328901Y165165D01*
X328679Y165137D01*
X328416Y165109D01*
X328125Y165096D01*
X327805Y165082D01*
X324352D01*
Y174678D01*
X328041D01*
X328291Y174665D01*
D02*
G37*
G36*
X365098Y172043D02*
X366290D01*
Y171128D01*
X365098D01*
Y167037D01*
Y167009D01*
Y166954D01*
Y166871D01*
X365112Y166774D01*
X365125Y166552D01*
X365139Y166455D01*
X365153Y166385D01*
X365167Y166357D01*
X365209Y166302D01*
X365264Y166233D01*
X365361Y166163D01*
X365389Y166150D01*
X365458Y166122D01*
X365583Y166094D01*
X365763Y166080D01*
X365902D01*
X365971Y166094D01*
X366068D01*
X366179Y166108D01*
X366290Y166122D01*
X366443Y165082D01*
X366415D01*
X366360Y165068D01*
X366263Y165054D01*
X366138Y165040D01*
X365999Y165012D01*
X365846Y164998D01*
X365541Y164984D01*
X365430D01*
X365320Y164998D01*
X365181Y165012D01*
X365014Y165026D01*
X364848Y165068D01*
X364695Y165109D01*
X364543Y165179D01*
X364529Y165193D01*
X364487Y165220D01*
X364432Y165262D01*
X364349Y165331D01*
X364279Y165401D01*
X364196Y165498D01*
X364113Y165595D01*
X364058Y165720D01*
Y165733D01*
X364030Y165789D01*
X364016Y165886D01*
X363988Y166025D01*
X363960Y166205D01*
X363946Y166316D01*
Y166441D01*
X363933Y166593D01*
X363919Y166746D01*
Y166912D01*
Y167106D01*
Y171128D01*
X363045D01*
Y172043D01*
X363919D01*
Y173763D01*
X365098Y174471D01*
Y172043D01*
D02*
G37*
G36*
X370534Y172182D02*
X370645Y172168D01*
X370784Y172141D01*
X370936Y172113D01*
X371116Y172071D01*
X371283Y172030D01*
X371477Y171960D01*
X371657Y171891D01*
X371852Y171794D01*
X372046Y171683D01*
X372240Y171558D01*
X372420Y171406D01*
X372587Y171239D01*
X372600Y171225D01*
X372628Y171198D01*
X372670Y171142D01*
X372725Y171059D01*
X372795Y170962D01*
X372864Y170851D01*
X372947Y170712D01*
X373030Y170546D01*
X373114Y170366D01*
X373197Y170171D01*
X373266Y169949D01*
X373335Y169714D01*
X373391Y169450D01*
X373433Y169173D01*
X373460Y168882D01*
X373474Y168563D01*
Y168549D01*
Y168493D01*
Y168396D01*
X373460Y168258D01*
X368260D01*
Y168244D01*
Y168202D01*
X368274Y168146D01*
Y168063D01*
X368287Y167966D01*
X368315Y167855D01*
X368357Y167606D01*
X368440Y167328D01*
X368551Y167023D01*
X368703Y166746D01*
X368898Y166496D01*
X368911D01*
X368925Y166469D01*
X369008Y166399D01*
X369133Y166302D01*
X369300Y166205D01*
X369522Y166094D01*
X369771Y165997D01*
X370049Y165928D01*
X370201Y165914D01*
X370368Y165900D01*
X370479D01*
X370603Y165914D01*
X370756Y165942D01*
X370922Y165983D01*
X371116Y166038D01*
X371297Y166122D01*
X371477Y166233D01*
X371491Y166247D01*
X371560Y166302D01*
X371643Y166385D01*
X371741Y166496D01*
X371852Y166649D01*
X371976Y166843D01*
X372101Y167065D01*
X372212Y167328D01*
X373433Y167176D01*
Y167162D01*
X373419Y167134D01*
X373405Y167079D01*
X373377Y166995D01*
X373335Y166912D01*
X373294Y166801D01*
X373183Y166565D01*
X373044Y166302D01*
X372850Y166025D01*
X372628Y165761D01*
X372351Y165511D01*
X372337D01*
X372309Y165484D01*
X372268Y165456D01*
X372212Y165415D01*
X372129Y165373D01*
X372046Y165331D01*
X371935Y165276D01*
X371810Y165220D01*
X371671Y165165D01*
X371533Y165109D01*
X371186Y165026D01*
X370798Y164957D01*
X370368Y164929D01*
X370215D01*
X370118Y164943D01*
X369993Y164957D01*
X369841Y164984D01*
X369674Y165012D01*
X369494Y165040D01*
X369106Y165151D01*
X368898Y165234D01*
X368703Y165317D01*
X368495Y165428D01*
X368301Y165553D01*
X368121Y165692D01*
X367941Y165858D01*
X367927Y165872D01*
X367899Y165900D01*
X367857Y165955D01*
X367802Y166038D01*
X367733Y166136D01*
X367663Y166247D01*
X367580Y166385D01*
X367497Y166538D01*
X367414Y166718D01*
X367330Y166912D01*
X367261Y167134D01*
X367192Y167370D01*
X367136Y167619D01*
X367095Y167897D01*
X367067Y168188D01*
X367053Y168493D01*
Y168507D01*
Y168576D01*
Y168660D01*
X367067Y168785D01*
X367081Y168937D01*
X367095Y169103D01*
X367122Y169298D01*
X367164Y169492D01*
X367275Y169936D01*
X367344Y170157D01*
X367427Y170393D01*
X367538Y170615D01*
X367663Y170823D01*
X367802Y171031D01*
X367954Y171225D01*
X367968Y171239D01*
X367996Y171267D01*
X368052Y171308D01*
X368121Y171378D01*
X368204Y171447D01*
X368315Y171530D01*
X368440Y171628D01*
X368592Y171711D01*
X368745Y171808D01*
X368925Y171891D01*
X369119Y171974D01*
X369328Y172043D01*
X369549Y172113D01*
X369785Y172155D01*
X370035Y172182D01*
X370298Y172196D01*
X370437D01*
X370534Y172182D01*
D02*
G37*
G36*
X314617Y174831D02*
X314741D01*
X314866Y174817D01*
X315033Y174790D01*
X315199Y174762D01*
X315560Y174692D01*
X315976Y174581D01*
X316378Y174415D01*
X316586Y174318D01*
X316794Y174207D01*
X316808Y174193D01*
X316836Y174179D01*
X316891Y174138D01*
X316974Y174096D01*
X317057Y174027D01*
X317168Y173944D01*
X317404Y173749D01*
X317654Y173500D01*
X317931Y173195D01*
X318195Y172834D01*
X318417Y172432D01*
Y172418D01*
X318444Y172376D01*
X318472Y172321D01*
X318500Y172238D01*
X318555Y172127D01*
X318597Y172002D01*
X318652Y171849D01*
X318708Y171683D01*
X318749Y171503D01*
X318805Y171308D01*
X318860Y171087D01*
X318902Y170865D01*
X318958Y170379D01*
X318985Y169852D01*
Y169838D01*
Y169783D01*
Y169714D01*
X318971Y169603D01*
Y169478D01*
X318958Y169325D01*
X318930Y169159D01*
X318916Y168979D01*
X318846Y168576D01*
X318736Y168133D01*
X318583Y167689D01*
X318500Y167467D01*
X318389Y167245D01*
Y167231D01*
X318361Y167190D01*
X318333Y167134D01*
X318278Y167051D01*
X318222Y166954D01*
X318153Y166857D01*
X317959Y166593D01*
X317723Y166316D01*
X317446Y166025D01*
X317113Y165747D01*
X316725Y165498D01*
X316711D01*
X316683Y165470D01*
X316614Y165442D01*
X316530Y165401D01*
X316433Y165359D01*
X316322Y165317D01*
X316184Y165262D01*
X316031Y165206D01*
X315865Y165151D01*
X315685Y165096D01*
X315282Y165012D01*
X314852Y164943D01*
X314395Y164915D01*
X314256D01*
X314173Y164929D01*
X314048D01*
X313909Y164957D01*
X313757Y164971D01*
X313577Y164998D01*
X313202Y165082D01*
X312800Y165193D01*
X312384Y165359D01*
X312176Y165456D01*
X311968Y165567D01*
X311954Y165581D01*
X311926Y165595D01*
X311871Y165636D01*
X311787Y165692D01*
X311704Y165747D01*
X311607Y165830D01*
X311371Y166038D01*
X311108Y166288D01*
X310831Y166593D01*
X310581Y166940D01*
X310345Y167342D01*
Y167356D01*
X310317Y167398D01*
X310290Y167453D01*
X310262Y167536D01*
X310220Y167647D01*
X310179Y167772D01*
X310123Y167911D01*
X310082Y168063D01*
X310026Y168244D01*
X309971Y168424D01*
X309888Y168840D01*
X309832Y169270D01*
X309804Y169741D01*
Y169755D01*
Y169769D01*
Y169852D01*
X309818Y169977D01*
Y170144D01*
X309846Y170338D01*
X309874Y170574D01*
X309915Y170837D01*
X309971Y171114D01*
X310026Y171406D01*
X310109Y171711D01*
X310220Y172016D01*
X310345Y172335D01*
X310484Y172640D01*
X310664Y172945D01*
X310858Y173222D01*
X311080Y173486D01*
X311094Y173500D01*
X311136Y173541D01*
X311219Y173611D01*
X311316Y173694D01*
X311441Y173805D01*
X311593Y173916D01*
X311774Y174041D01*
X311982Y174165D01*
X312204Y174290D01*
X312453Y174415D01*
X312731Y174526D01*
X313022Y174637D01*
X313341Y174720D01*
X313674Y174790D01*
X314020Y174831D01*
X314395Y174845D01*
X314520D01*
X314617Y174831D01*
D02*
G37*
G36*
X285562D02*
X285687D01*
X285812Y174817D01*
X285978Y174790D01*
X286145Y174762D01*
X286505Y174692D01*
X286921Y174581D01*
X287324Y174415D01*
X287532Y174318D01*
X287740Y174207D01*
X287754Y174193D01*
X287781Y174179D01*
X287837Y174138D01*
X287920Y174096D01*
X288003Y174027D01*
X288114Y173944D01*
X288350Y173749D01*
X288599Y173500D01*
X288877Y173195D01*
X289140Y172834D01*
X289362Y172432D01*
Y172418D01*
X289390Y172376D01*
X289418Y172321D01*
X289445Y172238D01*
X289501Y172127D01*
X289543Y172002D01*
X289598Y171849D01*
X289653Y171683D01*
X289695Y171503D01*
X289751Y171308D01*
X289806Y171087D01*
X289848Y170865D01*
X289903Y170379D01*
X289931Y169852D01*
Y169838D01*
Y169783D01*
Y169714D01*
X289917Y169603D01*
Y169478D01*
X289903Y169325D01*
X289875Y169159D01*
X289862Y168979D01*
X289792Y168576D01*
X289681Y168133D01*
X289529Y167689D01*
X289445Y167467D01*
X289335Y167245D01*
Y167231D01*
X289307Y167190D01*
X289279Y167134D01*
X289224Y167051D01*
X289168Y166954D01*
X289099Y166857D01*
X288905Y166593D01*
X288669Y166316D01*
X288391Y166025D01*
X288059Y165747D01*
X287670Y165498D01*
X287656D01*
X287629Y165470D01*
X287559Y165442D01*
X287476Y165401D01*
X287379Y165359D01*
X287268Y165317D01*
X287129Y165262D01*
X286977Y165206D01*
X286810Y165151D01*
X286630Y165096D01*
X286228Y165012D01*
X285798Y164943D01*
X285340Y164915D01*
X285202D01*
X285119Y164929D01*
X284994D01*
X284855Y164957D01*
X284702Y164971D01*
X284522Y164998D01*
X284148Y165082D01*
X283746Y165193D01*
X283330Y165359D01*
X283121Y165456D01*
X282913Y165567D01*
X282900Y165581D01*
X282872Y165595D01*
X282816Y165636D01*
X282733Y165692D01*
X282650Y165747D01*
X282553Y165830D01*
X282317Y166038D01*
X282054Y166288D01*
X281776Y166593D01*
X281527Y166940D01*
X281291Y167342D01*
Y167356D01*
X281263Y167398D01*
X281235Y167453D01*
X281208Y167536D01*
X281166Y167647D01*
X281124Y167772D01*
X281069Y167911D01*
X281027Y168063D01*
X280972Y168244D01*
X280916Y168424D01*
X280833Y168840D01*
X280778Y169270D01*
X280750Y169741D01*
Y169755D01*
Y169769D01*
Y169852D01*
X280764Y169977D01*
Y170144D01*
X280792Y170338D01*
X280819Y170574D01*
X280861Y170837D01*
X280916Y171114D01*
X280972Y171406D01*
X281055Y171711D01*
X281166Y172016D01*
X281291Y172335D01*
X281430Y172640D01*
X281610Y172945D01*
X281804Y173222D01*
X282026Y173486D01*
X282040Y173500D01*
X282081Y173541D01*
X282165Y173611D01*
X282262Y173694D01*
X282386Y173805D01*
X282539Y173916D01*
X282719Y174041D01*
X282927Y174165D01*
X283149Y174290D01*
X283399Y174415D01*
X283676Y174526D01*
X283967Y174637D01*
X284286Y174720D01*
X284619Y174790D01*
X284966Y174831D01*
X285340Y174845D01*
X285465D01*
X285562Y174831D01*
D02*
G37*
G36*
X351562Y172182D02*
X351659Y172168D01*
X351784Y172141D01*
X351923Y172113D01*
X352075Y172071D01*
X352228Y172016D01*
X352394Y171946D01*
X352561Y171863D01*
X352741Y171766D01*
X352907Y171655D01*
X353074Y171516D01*
X353240Y171364D01*
X353393Y171184D01*
Y172043D01*
X354474D01*
Y166025D01*
Y166011D01*
Y165955D01*
Y165872D01*
Y165761D01*
X354461Y165636D01*
Y165484D01*
X354447Y165317D01*
X354433Y165137D01*
X354391Y164763D01*
X354336Y164374D01*
X354294Y164194D01*
X354253Y164028D01*
X354197Y163875D01*
X354142Y163736D01*
Y163722D01*
X354128Y163709D01*
X354072Y163625D01*
X354003Y163501D01*
X353892Y163348D01*
X353739Y163182D01*
X353559Y163001D01*
X353337Y162821D01*
X353088Y162668D01*
X353074D01*
X353060Y162655D01*
X353018Y162627D01*
X352963Y162613D01*
X352893Y162571D01*
X352810Y162544D01*
X352602Y162474D01*
X352353Y162391D01*
X352048Y162336D01*
X351701Y162280D01*
X351326Y162266D01*
X351202D01*
X351118Y162280D01*
X351007D01*
X350896Y162294D01*
X350758Y162308D01*
X350605Y162336D01*
X350286Y162405D01*
X349953Y162502D01*
X349621Y162641D01*
X349315Y162835D01*
X349301Y162849D01*
X349288Y162863D01*
X349191Y162946D01*
X349080Y163071D01*
X348941Y163251D01*
X348802Y163487D01*
X348677Y163778D01*
X348636Y163944D01*
X348608Y164125D01*
X348580Y164305D01*
Y164513D01*
X349731Y164360D01*
Y164333D01*
X349745Y164277D01*
X349773Y164180D01*
X349801Y164055D01*
X349856Y163930D01*
X349926Y163806D01*
X350009Y163681D01*
X350120Y163584D01*
X350148Y163570D01*
X350203Y163528D01*
X350300Y163473D01*
X350439Y163417D01*
X350605Y163348D01*
X350813Y163293D01*
X351063Y163251D01*
X351326Y163237D01*
X351465D01*
X351604Y163251D01*
X351798Y163279D01*
X351992Y163320D01*
X352200Y163376D01*
X352408Y163459D01*
X352588Y163570D01*
X352602Y163584D01*
X352658Y163625D01*
X352741Y163709D01*
X352838Y163806D01*
X352935Y163944D01*
X353032Y164097D01*
X353129Y164277D01*
X353199Y164485D01*
Y164499D01*
X353212Y164555D01*
X353226Y164666D01*
X353240Y164804D01*
X353254Y164901D01*
Y165012D01*
X353268Y165137D01*
Y165276D01*
Y165428D01*
X353282Y165609D01*
Y165789D01*
Y165997D01*
X353268Y165983D01*
X353240Y165955D01*
X353199Y165914D01*
X353143Y165858D01*
X353074Y165789D01*
X352977Y165706D01*
X352866Y165623D01*
X352755Y165539D01*
X352463Y165373D01*
X352145Y165220D01*
X351964Y165165D01*
X351770Y165123D01*
X351562Y165096D01*
X351354Y165082D01*
X351285D01*
X351215Y165096D01*
X351118D01*
X350993Y165109D01*
X350855Y165137D01*
X350702Y165165D01*
X350536Y165206D01*
X350355Y165262D01*
X350175Y165331D01*
X349995Y165414D01*
X349801Y165511D01*
X349621Y165636D01*
X349440Y165775D01*
X349274Y165928D01*
X349121Y166108D01*
X349107Y166122D01*
X349094Y166150D01*
X349052Y166219D01*
X348996Y166288D01*
X348941Y166399D01*
X348872Y166510D01*
X348802Y166649D01*
X348733Y166815D01*
X348664Y166982D01*
X348594Y167176D01*
X348525Y167370D01*
X348469Y167592D01*
X348372Y168063D01*
X348358Y168327D01*
X348345Y168590D01*
Y168604D01*
Y168632D01*
Y168687D01*
Y168757D01*
X348358Y168854D01*
Y168951D01*
X348386Y169200D01*
X348428Y169478D01*
X348497Y169783D01*
X348580Y170102D01*
X348705Y170421D01*
Y170435D01*
X348719Y170462D01*
X348747Y170504D01*
X348774Y170560D01*
X348858Y170712D01*
X348969Y170906D01*
X349121Y171114D01*
X349301Y171322D01*
X349510Y171544D01*
X349745Y171724D01*
X349759D01*
X349773Y171738D01*
X349815Y171766D01*
X349870Y171794D01*
X350009Y171877D01*
X350203Y171960D01*
X350439Y172043D01*
X350716Y172127D01*
X351021Y172182D01*
X351354Y172196D01*
X351479D01*
X351562Y172182D01*
D02*
G37*
G36*
X285784Y150750D02*
X284453D01*
X280736Y160347D01*
X282123D01*
X284619Y153371D01*
Y153357D01*
X284633Y153329D01*
X284647Y153288D01*
X284675Y153232D01*
X284689Y153149D01*
X284716Y153066D01*
X284786Y152858D01*
X284869Y152622D01*
X284952Y152359D01*
X285119Y151804D01*
Y151818D01*
X285132Y151846D01*
X285146Y151887D01*
X285160Y151943D01*
X285202Y152095D01*
X285271Y152303D01*
X285340Y152539D01*
X285424Y152802D01*
X285521Y153080D01*
X285632Y153371D01*
X288239Y160347D01*
X289529D01*
X285784Y150750D01*
D02*
G37*
G36*
X295145Y154134D02*
X296449D01*
Y153052D01*
X295145D01*
Y150750D01*
X293967D01*
Y153052D01*
X289792D01*
Y154134D01*
X294188Y160347D01*
X295145D01*
Y154134D01*
D02*
G37*
G36*
X389111Y111171D02*
X383563D01*
X383550D01*
X383508D01*
X383439D01*
X383355D01*
X383258Y111157D01*
X383134D01*
X382870Y111144D01*
X382565Y111116D01*
X382260Y111074D01*
X381969Y111019D01*
X381844Y110991D01*
X381719Y110949D01*
X381691Y110935D01*
X381622Y110908D01*
X381525Y110838D01*
X381386Y110755D01*
X381247Y110658D01*
X381095Y110519D01*
X380942Y110353D01*
X380818Y110159D01*
X380804Y110131D01*
X380762Y110062D01*
X380720Y109937D01*
X380665Y109770D01*
X380596Y109576D01*
X380554Y109327D01*
X380513Y109063D01*
X380499Y108772D01*
Y108633D01*
X380513Y108550D01*
Y108425D01*
X380526Y108301D01*
X380582Y107995D01*
X380651Y107662D01*
X380762Y107344D01*
X380915Y107038D01*
X381012Y106900D01*
X381123Y106775D01*
X381137Y106761D01*
X381150Y106747D01*
X381192Y106720D01*
X381247Y106678D01*
X381331Y106636D01*
X381414Y106581D01*
X381539Y106525D01*
X381664Y106470D01*
X381816Y106414D01*
X381996Y106373D01*
X382204Y106317D01*
X382426Y106276D01*
X382676Y106234D01*
X382939Y106206D01*
X383245Y106179D01*
X383563D01*
X389111D01*
Y104903D01*
X383563D01*
X383550D01*
X383494D01*
X383425D01*
X383328D01*
X383203Y104917D01*
X383064D01*
X382898Y104930D01*
X382731Y104944D01*
X382357Y104986D01*
X381969Y105041D01*
X381594Y105125D01*
X381414Y105180D01*
X381247Y105236D01*
X381234D01*
X381206Y105249D01*
X381164Y105277D01*
X381109Y105305D01*
X380956Y105388D01*
X380762Y105513D01*
X380540Y105679D01*
X380318Y105873D01*
X380083Y106123D01*
X379874Y106428D01*
Y106442D01*
X379847Y106470D01*
X379833Y106511D01*
X379791Y106581D01*
X379750Y106664D01*
X379708Y106775D01*
X379666Y106886D01*
X379611Y107025D01*
X379556Y107177D01*
X379514Y107344D01*
X379472Y107524D01*
X379431Y107732D01*
X379403Y107940D01*
X379375Y108162D01*
X379347Y108661D01*
Y108786D01*
X379361Y108883D01*
Y108994D01*
X379375Y109133D01*
X379389Y109285D01*
X379403Y109438D01*
X379459Y109784D01*
X379542Y110159D01*
X379653Y110519D01*
X379805Y110866D01*
Y110880D01*
X379833Y110908D01*
X379861Y110949D01*
X379888Y111005D01*
X379999Y111157D01*
X380152Y111338D01*
X380346Y111546D01*
X380568Y111740D01*
X380845Y111934D01*
X381150Y112086D01*
X381164D01*
X381192Y112100D01*
X381247Y112114D01*
X381317Y112142D01*
X381400Y112170D01*
X381511Y112198D01*
X381636Y112239D01*
X381788Y112267D01*
X381955Y112295D01*
X382135Y112336D01*
X382329Y112364D01*
X382537Y112392D01*
X382773Y112419D01*
X383023Y112433D01*
X383286Y112447D01*
X383563D01*
X389111D01*
Y111171D01*
D02*
G37*
G36*
X386739Y102351D02*
X386767Y102323D01*
X386781Y102268D01*
X386823Y102198D01*
X386864Y102115D01*
X386920Y102018D01*
X387058Y101782D01*
X387211Y101505D01*
X387405Y101228D01*
X387627Y100936D01*
X387863Y100645D01*
X387877Y100631D01*
X387891Y100617D01*
X387932Y100576D01*
X387974Y100520D01*
X388112Y100395D01*
X388279Y100229D01*
X388473Y100063D01*
X388695Y99882D01*
X388917Y99730D01*
X389152Y99591D01*
Y98828D01*
X379514D01*
Y100007D01*
X387017D01*
X387003Y100021D01*
X386947Y100090D01*
X386864Y100174D01*
X386767Y100312D01*
X386642Y100465D01*
X386504Y100659D01*
X386351Y100881D01*
X386199Y101131D01*
Y101144D01*
X386185Y101158D01*
X386129Y101242D01*
X386060Y101380D01*
X385977Y101547D01*
X385880Y101741D01*
X385783Y101949D01*
X385685Y102157D01*
X385602Y102365D01*
X386739D01*
Y102351D01*
D02*
G37*
G36*
X370765Y497139D02*
X370862D01*
X370973Y497125D01*
X371236Y497069D01*
X371528Y497000D01*
X371833Y496889D01*
X372138Y496723D01*
X372290Y496626D01*
X372429Y496515D01*
X372443Y496501D01*
X372457Y496487D01*
X372498Y496445D01*
X372540Y496404D01*
X372609Y496334D01*
X372665Y496251D01*
X372817Y496057D01*
X372970Y495807D01*
X373109Y495502D01*
X373233Y495155D01*
X373317Y494767D01*
X372138Y494670D01*
Y494684D01*
X372124Y494698D01*
X372110Y494781D01*
X372068Y494906D01*
X372013Y495058D01*
X371958Y495225D01*
X371874Y495391D01*
X371777Y495544D01*
X371680Y495669D01*
X371652Y495696D01*
X371597Y495752D01*
X371500Y495835D01*
X371361Y495932D01*
X371181Y496015D01*
X370987Y496099D01*
X370751Y496154D01*
X370501Y496182D01*
X370404D01*
X370293Y496168D01*
X370168Y496140D01*
X370002Y496099D01*
X369836Y496043D01*
X369669Y495974D01*
X369503Y495863D01*
X369475Y495849D01*
X369406Y495793D01*
X369309Y495696D01*
X369184Y495558D01*
X369045Y495391D01*
X368893Y495197D01*
X368754Y494947D01*
X368615Y494670D01*
Y494656D01*
X368601Y494628D01*
X368587Y494587D01*
X368560Y494531D01*
X368546Y494448D01*
X368518Y494351D01*
X368490Y494240D01*
X368463Y494101D01*
X368421Y493949D01*
X368393Y493783D01*
X368366Y493602D01*
X368352Y493408D01*
X368324Y493186D01*
X368310Y492964D01*
X368296Y492715D01*
Y492465D01*
X368310Y492479D01*
X368366Y492562D01*
X368463Y492673D01*
X368587Y492812D01*
X368726Y492978D01*
X368907Y493131D01*
X369101Y493283D01*
X369323Y493422D01*
X369336D01*
X369350Y493436D01*
X369434Y493477D01*
X369558Y493519D01*
X369725Y493588D01*
X369919Y493644D01*
X370141Y493685D01*
X370377Y493727D01*
X370626Y493741D01*
X370737D01*
X370820Y493727D01*
X370931Y493713D01*
X371042Y493699D01*
X371181Y493671D01*
X371320Y493630D01*
X371639Y493533D01*
X371805Y493464D01*
X371971Y493366D01*
X372138Y493269D01*
X372318Y493158D01*
X372485Y493020D01*
X372637Y492867D01*
X372651Y492853D01*
X372679Y492826D01*
X372720Y492784D01*
X372762Y492715D01*
X372831Y492617D01*
X372901Y492520D01*
X372970Y492396D01*
X373053Y492257D01*
X373136Y492104D01*
X373206Y491938D01*
X373275Y491744D01*
X373344Y491550D01*
X373386Y491342D01*
X373428Y491106D01*
X373455Y490870D01*
X373469Y490620D01*
Y490607D01*
Y490579D01*
Y490537D01*
Y490468D01*
X373455Y490385D01*
Y490302D01*
X373414Y490080D01*
X373372Y489816D01*
X373303Y489539D01*
X373206Y489234D01*
X373067Y488942D01*
Y488928D01*
X373053Y488915D01*
X373025Y488873D01*
X372998Y488818D01*
X372914Y488679D01*
X372790Y488499D01*
X372637Y488304D01*
X372457Y488110D01*
X372235Y487916D01*
X371999Y487750D01*
X371985D01*
X371971Y487736D01*
X371930Y487708D01*
X371874Y487694D01*
X371736Y487625D01*
X371555Y487556D01*
X371320Y487472D01*
X371056Y487417D01*
X370765Y487361D01*
X370446Y487347D01*
X370377D01*
X370307Y487361D01*
X370196D01*
X370071Y487375D01*
X369933Y487403D01*
X369766Y487445D01*
X369600Y487486D01*
X369406Y487542D01*
X369212Y487611D01*
X369017Y487694D01*
X368809Y487805D01*
X368615Y487930D01*
X368421Y488069D01*
X368227Y488235D01*
X368047Y488429D01*
X368033Y488443D01*
X368005Y488485D01*
X367963Y488540D01*
X367908Y488637D01*
X367825Y488762D01*
X367755Y488901D01*
X367672Y489081D01*
X367589Y489275D01*
X367492Y489511D01*
X367409Y489775D01*
X367339Y490066D01*
X367270Y490385D01*
X367201Y490745D01*
X367159Y491134D01*
X367131Y491550D01*
X367118Y491993D01*
Y492007D01*
Y492021D01*
Y492063D01*
Y492118D01*
X367131Y492257D01*
Y492451D01*
X367145Y492673D01*
X367173Y492937D01*
X367201Y493228D01*
X367242Y493547D01*
X367298Y493866D01*
X367367Y494212D01*
X367450Y494545D01*
X367547Y494878D01*
X367672Y495197D01*
X367811Y495502D01*
X367963Y495793D01*
X368144Y496043D01*
X368158Y496057D01*
X368185Y496085D01*
X368241Y496140D01*
X368310Y496223D01*
X368393Y496306D01*
X368504Y496390D01*
X368643Y496501D01*
X368782Y496598D01*
X368948Y496695D01*
X369128Y496806D01*
X369336Y496889D01*
X369544Y496986D01*
X369780Y497055D01*
X370030Y497111D01*
X370293Y497139D01*
X370571Y497152D01*
X370682D01*
X370765Y497139D01*
D02*
G37*
G36*
X363012D02*
X363193Y497111D01*
X363415Y497069D01*
X363664Y497000D01*
X363914Y496917D01*
X364164Y496806D01*
X364177D01*
X364191Y496792D01*
X364274Y496750D01*
X364399Y496667D01*
X364538Y496570D01*
X364704Y496431D01*
X364871Y496279D01*
X365037Y496099D01*
X365176Y495890D01*
X365190Y495863D01*
X365231Y495793D01*
X365287Y495669D01*
X365356Y495516D01*
X365425Y495336D01*
X365481Y495128D01*
X365523Y494892D01*
X365536Y494656D01*
Y494628D01*
Y494545D01*
X365523Y494434D01*
X365495Y494282D01*
X365453Y494101D01*
X365384Y493907D01*
X365301Y493713D01*
X365190Y493519D01*
X365176Y493491D01*
X365134Y493436D01*
X365051Y493339D01*
X364940Y493228D01*
X364801Y493103D01*
X364635Y492964D01*
X364441Y492839D01*
X364205Y492715D01*
X364219D01*
X364247Y492701D01*
X364288Y492687D01*
X364344Y492673D01*
X364496Y492617D01*
X364691Y492534D01*
X364912Y492423D01*
X365134Y492285D01*
X365342Y492104D01*
X365536Y491896D01*
X365550Y491869D01*
X365606Y491785D01*
X365689Y491647D01*
X365772Y491466D01*
X365855Y491245D01*
X365939Y490981D01*
X365994Y490676D01*
X366008Y490343D01*
Y490329D01*
Y490288D01*
Y490218D01*
X365994Y490135D01*
X365980Y490024D01*
X365952Y489899D01*
X365925Y489761D01*
X365897Y489608D01*
X365786Y489275D01*
X365703Y489095D01*
X365620Y488928D01*
X365509Y488748D01*
X365384Y488568D01*
X365245Y488388D01*
X365079Y488221D01*
X365065Y488207D01*
X365037Y488180D01*
X364982Y488138D01*
X364912Y488083D01*
X364829Y488013D01*
X364718Y487944D01*
X364593Y487861D01*
X364441Y487791D01*
X364288Y487708D01*
X364108Y487625D01*
X363928Y487556D01*
X363720Y487486D01*
X363498Y487431D01*
X363262Y487389D01*
X363026Y487361D01*
X362763Y487347D01*
X362638D01*
X362555Y487361D01*
X362444Y487375D01*
X362319Y487389D01*
X362180Y487417D01*
X362028Y487445D01*
X361695Y487528D01*
X361348Y487667D01*
X361168Y487750D01*
X361002Y487847D01*
X360835Y487972D01*
X360669Y488096D01*
X360655Y488110D01*
X360627Y488138D01*
X360585Y488180D01*
X360544Y488235D01*
X360475Y488304D01*
X360405Y488401D01*
X360322Y488499D01*
X360239Y488623D01*
X360155Y488762D01*
X360072Y488901D01*
X359920Y489234D01*
X359795Y489622D01*
X359753Y489830D01*
X359726Y490052D01*
X360904Y490204D01*
Y490191D01*
X360918Y490163D01*
X360932Y490107D01*
X360946Y490038D01*
X360960Y489955D01*
X360988Y489858D01*
X361057Y489650D01*
X361154Y489400D01*
X361279Y489164D01*
X361418Y488942D01*
X361584Y488748D01*
X361612Y488734D01*
X361667Y488679D01*
X361778Y488610D01*
X361917Y488540D01*
X362083Y488457D01*
X362291Y488388D01*
X362527Y488332D01*
X362777Y488318D01*
X362860D01*
X362915Y488332D01*
X363068Y488346D01*
X363262Y488388D01*
X363484Y488457D01*
X363720Y488554D01*
X363955Y488693D01*
X364177Y488887D01*
X364205Y488915D01*
X364274Y488998D01*
X364358Y489123D01*
X364469Y489289D01*
X364580Y489497D01*
X364663Y489733D01*
X364732Y490010D01*
X364760Y490315D01*
Y490329D01*
Y490357D01*
Y490399D01*
X364746Y490454D01*
X364732Y490607D01*
X364691Y490787D01*
X364635Y491009D01*
X364538Y491231D01*
X364399Y491453D01*
X364219Y491661D01*
X364191Y491688D01*
X364122Y491744D01*
X364011Y491827D01*
X363858Y491924D01*
X363664Y492021D01*
X363428Y492104D01*
X363165Y492160D01*
X362874Y492188D01*
X362749D01*
X362652Y492174D01*
X362527Y492160D01*
X362388Y492132D01*
X362222Y492104D01*
X362042Y492063D01*
X362180Y493103D01*
X362250D01*
X362305Y493089D01*
X362485D01*
X362638Y493117D01*
X362818Y493144D01*
X363026Y493186D01*
X363262Y493256D01*
X363484Y493353D01*
X363720Y493477D01*
X363734D01*
X363747Y493491D01*
X363817Y493547D01*
X363914Y493644D01*
X364025Y493769D01*
X364136Y493949D01*
X364233Y494157D01*
X364302Y494393D01*
X364330Y494531D01*
Y494684D01*
Y494698D01*
Y494712D01*
Y494795D01*
X364302Y494906D01*
X364274Y495058D01*
X364219Y495225D01*
X364150Y495405D01*
X364039Y495585D01*
X363886Y495752D01*
X363872Y495766D01*
X363803Y495821D01*
X363706Y495890D01*
X363581Y495974D01*
X363415Y496043D01*
X363220Y496112D01*
X362999Y496168D01*
X362749Y496182D01*
X362638D01*
X362513Y496154D01*
X362347Y496126D01*
X362166Y496071D01*
X361986Y496001D01*
X361792Y495890D01*
X361612Y495752D01*
X361598Y495738D01*
X361542Y495669D01*
X361459Y495572D01*
X361362Y495433D01*
X361265Y495252D01*
X361168Y495031D01*
X361085Y494767D01*
X361029Y494462D01*
X359850Y494670D01*
Y494684D01*
X359864Y494725D01*
X359878Y494781D01*
X359892Y494864D01*
X359920Y494961D01*
X359961Y495072D01*
X360045Y495336D01*
X360183Y495641D01*
X360350Y495946D01*
X360558Y496237D01*
X360821Y496501D01*
X360835Y496515D01*
X360863Y496528D01*
X360904Y496556D01*
X360960Y496598D01*
X361029Y496653D01*
X361126Y496709D01*
X361223Y496764D01*
X361348Y496833D01*
X361626Y496944D01*
X361945Y497055D01*
X362319Y497125D01*
X362513Y497152D01*
X362860D01*
X363012Y497139D01*
D02*
G37*
G36*
X355093Y497097D02*
X355218D01*
X355510Y497083D01*
X355815Y497042D01*
X356147Y497000D01*
X356453Y496931D01*
X356605Y496889D01*
X356730Y496847D01*
X356744D01*
X356758Y496833D01*
X356841Y496792D01*
X356966Y496736D01*
X357118Y496639D01*
X357285Y496515D01*
X357465Y496348D01*
X357631Y496154D01*
X357798Y495932D01*
Y495918D01*
X357812Y495904D01*
X357867Y495821D01*
X357923Y495682D01*
X358006Y495502D01*
X358075Y495294D01*
X358145Y495045D01*
X358186Y494781D01*
X358200Y494490D01*
Y494476D01*
Y494448D01*
Y494393D01*
X358186Y494323D01*
Y494226D01*
X358172Y494129D01*
X358117Y493893D01*
X358034Y493616D01*
X357923Y493325D01*
X357756Y493034D01*
X357645Y492895D01*
X357534Y492756D01*
X357520Y492742D01*
X357507Y492729D01*
X357465Y492687D01*
X357410Y492645D01*
X357340Y492590D01*
X357257Y492534D01*
X357146Y492465D01*
X357035Y492382D01*
X356896Y492312D01*
X356744Y492243D01*
X356577Y492160D01*
X356397Y492090D01*
X356189Y492035D01*
X355981Y491966D01*
X355745Y491924D01*
X355496Y491883D01*
X355523Y491869D01*
X355579Y491841D01*
X355662Y491785D01*
X355773Y491730D01*
X356023Y491577D01*
X356147Y491480D01*
X356259Y491397D01*
X356286Y491369D01*
X356356Y491300D01*
X356466Y491189D01*
X356605Y491050D01*
X356758Y490856D01*
X356938Y490648D01*
X357118Y490399D01*
X357313Y490121D01*
X358963Y487514D01*
X357382D01*
X356120Y489511D01*
Y489525D01*
X356092Y489553D01*
X356064Y489594D01*
X356023Y489650D01*
X355926Y489802D01*
X355801Y489996D01*
X355648Y490204D01*
X355496Y490426D01*
X355343Y490634D01*
X355205Y490829D01*
X355191Y490842D01*
X355149Y490898D01*
X355080Y490981D01*
X354983Y491078D01*
X354775Y491286D01*
X354664Y491383D01*
X354553Y491466D01*
X354539Y491480D01*
X354511Y491494D01*
X354456Y491522D01*
X354372Y491563D01*
X354289Y491605D01*
X354192Y491647D01*
X353970Y491716D01*
X353956D01*
X353929Y491730D01*
X353873D01*
X353804Y491744D01*
X353707Y491758D01*
X353596D01*
X353443Y491772D01*
X351807D01*
Y487514D01*
X350531D01*
Y497111D01*
X354983D01*
X355093Y497097D01*
D02*
G37*
G36*
X286942Y432655D02*
X287053Y432641D01*
X287178Y432627D01*
X287330Y432599D01*
X287483Y432572D01*
X287843Y432489D01*
X288218Y432350D01*
X288412Y432267D01*
X288592Y432156D01*
X288786Y432045D01*
X288967Y431906D01*
X288981Y431892D01*
X289022Y431865D01*
X289078Y431809D01*
X289147Y431740D01*
X289230Y431643D01*
X289341Y431532D01*
X289438Y431393D01*
X289549Y431240D01*
X289660Y431074D01*
X289757Y430880D01*
X289854Y430672D01*
X289951Y430450D01*
X290021Y430214D01*
X290076Y429951D01*
X290118Y429673D01*
X290132Y429382D01*
Y429257D01*
X290118Y429160D01*
X290104Y429049D01*
X290090Y428924D01*
X290076Y428772D01*
X290035Y428619D01*
X289951Y428273D01*
X289827Y427926D01*
X289743Y427746D01*
X289646Y427565D01*
X289535Y427399D01*
X289410Y427232D01*
X289397Y427219D01*
X289383Y427191D01*
X289327Y427163D01*
X289272Y427108D01*
X289202Y427038D01*
X289119Y426969D01*
X289008Y426886D01*
X288883Y426816D01*
X288759Y426733D01*
X288606Y426650D01*
X288273Y426497D01*
X287885Y426373D01*
X287677Y426331D01*
X287455Y426303D01*
X287358Y427537D01*
X287372D01*
X287400D01*
X287441Y427551D01*
X287511Y427565D01*
X287663Y427607D01*
X287871Y427662D01*
X288079Y427746D01*
X288315Y427856D01*
X288523Y427995D01*
X288717Y428162D01*
X288731Y428189D01*
X288786Y428245D01*
X288856Y428356D01*
X288939Y428508D01*
X289022Y428675D01*
X289091Y428883D01*
X289147Y429118D01*
X289161Y429382D01*
Y429465D01*
X289147Y429521D01*
X289133Y429687D01*
X289078Y429881D01*
X289008Y430117D01*
X288897Y430353D01*
X288731Y430602D01*
X288634Y430713D01*
X288523Y430824D01*
X288509Y430838D01*
X288495Y430852D01*
X288454Y430880D01*
X288412Y430921D01*
X288259Y431018D01*
X288065Y431129D01*
X287829Y431227D01*
X287538Y431324D01*
X287192Y431393D01*
X287011Y431421D01*
X286817D01*
X286803D01*
X286775D01*
X286720D01*
X286651Y431407D01*
X286567D01*
X286470Y431393D01*
X286248Y431351D01*
X285985Y431282D01*
X285721Y431185D01*
X285472Y431046D01*
X285236Y430852D01*
X285222D01*
X285208Y430824D01*
X285139Y430755D01*
X285042Y430630D01*
X284931Y430464D01*
X284834Y430242D01*
X284737Y429992D01*
X284667Y429701D01*
X284640Y429535D01*
Y429271D01*
X284654Y429160D01*
X284667Y429021D01*
X284709Y428855D01*
X284751Y428689D01*
X284820Y428508D01*
X284903Y428328D01*
X284917Y428314D01*
X284945Y428259D01*
X285014Y428176D01*
X285084Y428064D01*
X285181Y427954D01*
X285305Y427843D01*
X285430Y427718D01*
X285583Y427621D01*
X285430Y426511D01*
X280493Y427440D01*
Y432211D01*
X281616D01*
Y428370D01*
X284210Y427856D01*
X284196Y427870D01*
X284182Y427898D01*
X284154Y427940D01*
X284113Y428009D01*
X284071Y428092D01*
X284016Y428189D01*
X283905Y428411D01*
X283794Y428689D01*
X283697Y428994D01*
X283627Y429327D01*
X283600Y429493D01*
Y429798D01*
X283613Y429881D01*
X283627Y429992D01*
X283641Y430117D01*
X283669Y430256D01*
X283711Y430408D01*
X283808Y430741D01*
X283877Y430921D01*
X283974Y431102D01*
X284071Y431282D01*
X284182Y431462D01*
X284321Y431629D01*
X284473Y431795D01*
X284487Y431809D01*
X284515Y431837D01*
X284557Y431878D01*
X284626Y431934D01*
X284723Y432003D01*
X284820Y432072D01*
X284945Y432156D01*
X285084Y432239D01*
X285236Y432308D01*
X285403Y432392D01*
X285597Y432461D01*
X285791Y432530D01*
X285999Y432586D01*
X286235Y432627D01*
X286470Y432655D01*
X286720Y432669D01*
X286734D01*
X286775D01*
X286845D01*
X286942Y432655D01*
D02*
G37*
G36*
X285902Y421810D02*
X289965D01*
Y420534D01*
X285902D01*
X280368Y416831D01*
Y418371D01*
X283281Y420257D01*
X283295D01*
X283322Y420284D01*
X283364Y420312D01*
X283419Y420340D01*
X283489Y420395D01*
X283572Y420451D01*
X283780Y420576D01*
X284030Y420728D01*
X284307Y420895D01*
X284598Y421075D01*
X284903Y421241D01*
X284889D01*
X284862Y421255D01*
X284820Y421283D01*
X284765Y421325D01*
X284695Y421366D01*
X284612Y421422D01*
X284404Y421546D01*
X284154Y421699D01*
X283863Y421879D01*
X283544Y422087D01*
X283197Y422309D01*
X280368Y424154D01*
Y425638D01*
X285902Y421810D01*
D02*
G37*
G36*
X292352Y437127D02*
X292421Y437113D01*
X292505Y437086D01*
X292588Y437044D01*
X292685Y436989D01*
X292768Y436919D01*
X292782Y436905D01*
X292796Y436878D01*
X292837Y436836D01*
X292865Y436767D01*
X292948Y436614D01*
X292962Y436517D01*
X292976Y436406D01*
Y436351D01*
X292962Y436295D01*
X292948Y436226D01*
X292920Y436143D01*
X292893Y436059D01*
X292837Y435962D01*
X292768Y435879D01*
X292754Y435865D01*
X292726Y435851D01*
X292685Y435810D01*
X292615Y435782D01*
X292546Y435741D01*
X292449Y435699D01*
X292352Y435685D01*
X292241Y435671D01*
X292227D01*
X292185D01*
X292130Y435685D01*
X292061Y435699D01*
X291978Y435727D01*
X291894Y435754D01*
X291811Y435810D01*
X291728Y435879D01*
X291714Y435893D01*
X291686Y435921D01*
X291658Y435962D01*
X291617Y436032D01*
X291575Y436101D01*
X291534Y436198D01*
X291520Y436295D01*
X291506Y436406D01*
Y436462D01*
X291520Y436517D01*
X291534Y436586D01*
X291561Y436670D01*
X291603Y436753D01*
X291658Y436836D01*
X291728Y436919D01*
X291742Y436933D01*
X291769Y436961D01*
X291811Y436989D01*
X291880Y437030D01*
X292033Y437113D01*
X292130Y437127D01*
X292241Y437141D01*
X292255D01*
X292296D01*
X292352Y437127D01*
D02*
G37*
G36*
X390728Y497139D02*
X390908Y497111D01*
X391130Y497069D01*
X391380Y497000D01*
X391629Y496917D01*
X391879Y496806D01*
X391893D01*
X391907Y496792D01*
X391990Y496750D01*
X392115Y496667D01*
X392253Y496570D01*
X392420Y496431D01*
X392586Y496279D01*
X392752Y496099D01*
X392891Y495890D01*
X392905Y495863D01*
X392947Y495793D01*
X393002Y495669D01*
X393072Y495516D01*
X393141Y495336D01*
X393196Y495128D01*
X393238Y494892D01*
X393252Y494656D01*
Y494628D01*
Y494545D01*
X393238Y494434D01*
X393210Y494282D01*
X393169Y494101D01*
X393099Y493907D01*
X393016Y493713D01*
X392905Y493519D01*
X392891Y493491D01*
X392850Y493436D01*
X392766Y493339D01*
X392655Y493228D01*
X392517Y493103D01*
X392350Y492964D01*
X392156Y492839D01*
X391920Y492715D01*
X391934D01*
X391962Y492701D01*
X392004Y492687D01*
X392059Y492673D01*
X392212Y492617D01*
X392406Y492534D01*
X392628Y492423D01*
X392850Y492285D01*
X393058Y492104D01*
X393252Y491896D01*
X393266Y491869D01*
X393321Y491785D01*
X393404Y491647D01*
X393488Y491466D01*
X393571Y491245D01*
X393654Y490981D01*
X393709Y490676D01*
X393723Y490343D01*
Y490329D01*
Y490288D01*
Y490218D01*
X393709Y490135D01*
X393696Y490024D01*
X393668Y489899D01*
X393640Y489761D01*
X393612Y489608D01*
X393501Y489275D01*
X393418Y489095D01*
X393335Y488928D01*
X393224Y488748D01*
X393099Y488568D01*
X392961Y488388D01*
X392794Y488221D01*
X392780Y488207D01*
X392752Y488180D01*
X392697Y488138D01*
X392628Y488083D01*
X392545Y488013D01*
X392434Y487944D01*
X392309Y487861D01*
X392156Y487791D01*
X392004Y487708D01*
X391823Y487625D01*
X391643Y487556D01*
X391435Y487486D01*
X391213Y487431D01*
X390977Y487389D01*
X390742Y487361D01*
X390478Y487347D01*
X390353D01*
X390270Y487361D01*
X390159Y487375D01*
X390034Y487389D01*
X389896Y487417D01*
X389743Y487445D01*
X389410Y487528D01*
X389063Y487667D01*
X388883Y487750D01*
X388717Y487847D01*
X388550Y487972D01*
X388384Y488096D01*
X388370Y488110D01*
X388342Y488138D01*
X388301Y488180D01*
X388259Y488235D01*
X388190Y488304D01*
X388120Y488401D01*
X388037Y488499D01*
X387954Y488623D01*
X387871Y488762D01*
X387788Y488901D01*
X387635Y489234D01*
X387510Y489622D01*
X387469Y489830D01*
X387441Y490052D01*
X388620Y490204D01*
Y490191D01*
X388634Y490163D01*
X388647Y490107D01*
X388661Y490038D01*
X388675Y489955D01*
X388703Y489858D01*
X388772Y489650D01*
X388869Y489400D01*
X388994Y489164D01*
X389133Y488942D01*
X389299Y488748D01*
X389327Y488734D01*
X389383Y488679D01*
X389493Y488610D01*
X389632Y488540D01*
X389799Y488457D01*
X390007Y488388D01*
X390242Y488332D01*
X390492Y488318D01*
X390575D01*
X390631Y488332D01*
X390783Y488346D01*
X390977Y488388D01*
X391199Y488457D01*
X391435Y488554D01*
X391671Y488693D01*
X391893Y488887D01*
X391920Y488915D01*
X391990Y488998D01*
X392073Y489123D01*
X392184Y489289D01*
X392295Y489497D01*
X392378Y489733D01*
X392447Y490010D01*
X392475Y490315D01*
Y490329D01*
Y490357D01*
Y490399D01*
X392461Y490454D01*
X392447Y490607D01*
X392406Y490787D01*
X392350Y491009D01*
X392253Y491231D01*
X392115Y491453D01*
X391934Y491661D01*
X391907Y491688D01*
X391837Y491744D01*
X391726Y491827D01*
X391574Y491924D01*
X391380Y492021D01*
X391144Y492104D01*
X390880Y492160D01*
X390589Y492188D01*
X390464D01*
X390367Y492174D01*
X390242Y492160D01*
X390104Y492132D01*
X389937Y492104D01*
X389757Y492063D01*
X389896Y493103D01*
X389965D01*
X390020Y493089D01*
X390201D01*
X390353Y493117D01*
X390534Y493144D01*
X390742Y493186D01*
X390977Y493256D01*
X391199Y493353D01*
X391435Y493477D01*
X391449D01*
X391463Y493491D01*
X391532Y493547D01*
X391629Y493644D01*
X391740Y493769D01*
X391851Y493949D01*
X391948Y494157D01*
X392018Y494393D01*
X392045Y494531D01*
Y494684D01*
Y494698D01*
Y494712D01*
Y494795D01*
X392018Y494906D01*
X391990Y495058D01*
X391934Y495225D01*
X391865Y495405D01*
X391754Y495585D01*
X391601Y495752D01*
X391588Y495766D01*
X391518Y495821D01*
X391421Y495890D01*
X391296Y495974D01*
X391130Y496043D01*
X390936Y496112D01*
X390714Y496168D01*
X390464Y496182D01*
X390353D01*
X390229Y496154D01*
X390062Y496126D01*
X389882Y496071D01*
X389701Y496001D01*
X389507Y495890D01*
X389327Y495752D01*
X389313Y495738D01*
X389258Y495669D01*
X389174Y495572D01*
X389077Y495433D01*
X388980Y495252D01*
X388883Y495031D01*
X388800Y494767D01*
X388745Y494462D01*
X387566Y494670D01*
Y494684D01*
X387580Y494725D01*
X387593Y494781D01*
X387607Y494864D01*
X387635Y494961D01*
X387677Y495072D01*
X387760Y495336D01*
X387899Y495641D01*
X388065Y495946D01*
X388273Y496237D01*
X388536Y496501D01*
X388550Y496515D01*
X388578Y496528D01*
X388620Y496556D01*
X388675Y496598D01*
X388745Y496653D01*
X388842Y496709D01*
X388939Y496764D01*
X389063Y496833D01*
X389341Y496944D01*
X389660Y497055D01*
X390034Y497125D01*
X390229Y497152D01*
X390575D01*
X390728Y497139D01*
D02*
G37*
G36*
X400796Y495863D02*
X396955D01*
X396441Y493269D01*
X396455Y493283D01*
X396483Y493297D01*
X396525Y493325D01*
X396594Y493366D01*
X396677Y493408D01*
X396774Y493464D01*
X396996Y493574D01*
X397274Y493685D01*
X397579Y493783D01*
X397911Y493852D01*
X398078Y493880D01*
X398383D01*
X398466Y493866D01*
X398577Y493852D01*
X398702Y493838D01*
X398841Y493810D01*
X398993Y493769D01*
X399326Y493671D01*
X399506Y493602D01*
X399687Y493505D01*
X399867Y493408D01*
X400047Y493297D01*
X400214Y493158D01*
X400380Y493006D01*
X400394Y492992D01*
X400422Y492964D01*
X400463Y492923D01*
X400519Y492853D01*
X400588Y492756D01*
X400658Y492659D01*
X400741Y492534D01*
X400824Y492396D01*
X400893Y492243D01*
X400976Y492077D01*
X401046Y491883D01*
X401115Y491688D01*
X401171Y491480D01*
X401212Y491245D01*
X401240Y491009D01*
X401254Y490759D01*
Y490745D01*
Y490704D01*
Y490634D01*
X401240Y490537D01*
X401226Y490426D01*
X401212Y490302D01*
X401185Y490149D01*
X401157Y489996D01*
X401073Y489636D01*
X400935Y489261D01*
X400852Y489067D01*
X400741Y488887D01*
X400630Y488693D01*
X400491Y488512D01*
X400477Y488499D01*
X400449Y488457D01*
X400394Y488401D01*
X400325Y488332D01*
X400228Y488249D01*
X400117Y488138D01*
X399978Y488041D01*
X399825Y487930D01*
X399659Y487819D01*
X399465Y487722D01*
X399257Y487625D01*
X399035Y487528D01*
X398799Y487458D01*
X398536Y487403D01*
X398258Y487361D01*
X397967Y487347D01*
X397842D01*
X397745Y487361D01*
X397634Y487375D01*
X397509Y487389D01*
X397357Y487403D01*
X397204Y487445D01*
X396858Y487528D01*
X396511Y487653D01*
X396331Y487736D01*
X396150Y487833D01*
X395984Y487944D01*
X395817Y488069D01*
X395804Y488083D01*
X395776Y488096D01*
X395748Y488152D01*
X395693Y488207D01*
X395623Y488277D01*
X395554Y488360D01*
X395471Y488471D01*
X395401Y488596D01*
X395318Y488721D01*
X395235Y488873D01*
X395082Y489206D01*
X394958Y489594D01*
X394916Y489802D01*
X394888Y490024D01*
X396123Y490121D01*
Y490107D01*
Y490080D01*
X396136Y490038D01*
X396150Y489969D01*
X396192Y489816D01*
X396247Y489608D01*
X396331Y489400D01*
X396441Y489164D01*
X396580Y488956D01*
X396747Y488762D01*
X396774Y488748D01*
X396830Y488693D01*
X396941Y488623D01*
X397093Y488540D01*
X397260Y488457D01*
X397468Y488388D01*
X397704Y488332D01*
X397967Y488318D01*
X398050D01*
X398106Y488332D01*
X398272Y488346D01*
X398466Y488401D01*
X398702Y488471D01*
X398938Y488582D01*
X399187Y488748D01*
X399298Y488845D01*
X399409Y488956D01*
X399423Y488970D01*
X399437Y488984D01*
X399465Y489026D01*
X399506Y489067D01*
X399604Y489220D01*
X399714Y489414D01*
X399812Y489650D01*
X399909Y489941D01*
X399978Y490288D01*
X400006Y490468D01*
Y490662D01*
Y490676D01*
Y490704D01*
Y490759D01*
X399992Y490829D01*
Y490912D01*
X399978Y491009D01*
X399936Y491231D01*
X399867Y491494D01*
X399770Y491758D01*
X399631Y492007D01*
X399437Y492243D01*
Y492257D01*
X399409Y492271D01*
X399340Y492340D01*
X399215Y492437D01*
X399049Y492548D01*
X398827Y492645D01*
X398577Y492742D01*
X398286Y492812D01*
X398120Y492839D01*
X397856D01*
X397745Y492826D01*
X397606Y492812D01*
X397440Y492770D01*
X397274Y492729D01*
X397093Y492659D01*
X396913Y492576D01*
X396899Y492562D01*
X396844Y492534D01*
X396760Y492465D01*
X396650Y492396D01*
X396539Y492299D01*
X396428Y492174D01*
X396303Y492049D01*
X396206Y491896D01*
X395096Y492049D01*
X396025Y496986D01*
X400796D01*
Y495863D01*
D02*
G37*
G36*
X382809Y497097D02*
X382934D01*
X383225Y497083D01*
X383530Y497042D01*
X383863Y497000D01*
X384168Y496931D01*
X384320Y496889D01*
X384445Y496847D01*
X384459D01*
X384473Y496833D01*
X384556Y496792D01*
X384681Y496736D01*
X384834Y496639D01*
X385000Y496515D01*
X385180Y496348D01*
X385347Y496154D01*
X385513Y495932D01*
Y495918D01*
X385527Y495904D01*
X385583Y495821D01*
X385638Y495682D01*
X385721Y495502D01*
X385791Y495294D01*
X385860Y495045D01*
X385901Y494781D01*
X385915Y494490D01*
Y494476D01*
Y494448D01*
Y494393D01*
X385901Y494323D01*
Y494226D01*
X385888Y494129D01*
X385832Y493893D01*
X385749Y493616D01*
X385638Y493325D01*
X385472Y493034D01*
X385361Y492895D01*
X385250Y492756D01*
X385236Y492742D01*
X385222Y492729D01*
X385180Y492687D01*
X385125Y492645D01*
X385056Y492590D01*
X384972Y492534D01*
X384861Y492465D01*
X384750Y492382D01*
X384612Y492312D01*
X384459Y492243D01*
X384293Y492160D01*
X384113Y492090D01*
X383904Y492035D01*
X383696Y491966D01*
X383461Y491924D01*
X383211Y491883D01*
X383239Y491869D01*
X383294Y491841D01*
X383377Y491785D01*
X383488Y491730D01*
X383738Y491577D01*
X383863Y491480D01*
X383974Y491397D01*
X384002Y491369D01*
X384071Y491300D01*
X384182Y491189D01*
X384320Y491050D01*
X384473Y490856D01*
X384653Y490648D01*
X384834Y490399D01*
X385028Y490121D01*
X386678Y487514D01*
X385097D01*
X383835Y489511D01*
Y489525D01*
X383807Y489553D01*
X383780Y489594D01*
X383738Y489650D01*
X383641Y489802D01*
X383516Y489996D01*
X383364Y490204D01*
X383211Y490426D01*
X383059Y490634D01*
X382920Y490829D01*
X382906Y490842D01*
X382864Y490898D01*
X382795Y490981D01*
X382698Y491078D01*
X382490Y491286D01*
X382379Y491383D01*
X382268Y491466D01*
X382254Y491480D01*
X382226Y491494D01*
X382171Y491522D01*
X382088Y491563D01*
X382005Y491605D01*
X381907Y491647D01*
X381685Y491716D01*
X381672D01*
X381644Y491730D01*
X381588D01*
X381519Y491744D01*
X381422Y491758D01*
X381311D01*
X381158Y491772D01*
X379522D01*
Y487514D01*
X378246D01*
Y497111D01*
X382698D01*
X382809Y497097D01*
D02*
G37*
G36*
X17486Y175000D02*
X16308D01*
Y182503D01*
X16294Y182489D01*
X16224Y182433D01*
X16141Y182350D01*
X16003Y182253D01*
X15850Y182128D01*
X15656Y181990D01*
X15434Y181837D01*
X15184Y181685D01*
X15170D01*
X15157Y181671D01*
X15073Y181615D01*
X14935Y181546D01*
X14768Y181463D01*
X14574Y181366D01*
X14366Y181269D01*
X14158Y181171D01*
X13950Y181088D01*
Y182225D01*
X13964D01*
X13992Y182253D01*
X14047Y182267D01*
X14116Y182309D01*
X14200Y182350D01*
X14297Y182406D01*
X14532Y182544D01*
X14810Y182697D01*
X15087Y182891D01*
X15378Y183113D01*
X15670Y183349D01*
X15683Y183363D01*
X15697Y183377D01*
X15739Y183418D01*
X15795Y183460D01*
X15919Y183598D01*
X16086Y183765D01*
X16252Y183959D01*
X16432Y184181D01*
X16585Y184403D01*
X16724Y184639D01*
X17486D01*
Y175000D01*
D02*
G37*
G36*
X82592Y178942D02*
X82703Y178928D01*
X82842Y178915D01*
X82994Y178887D01*
X83147Y178859D01*
X83507Y178762D01*
X83868Y178623D01*
X84048Y178540D01*
X84228Y178443D01*
X84395Y178318D01*
X84547Y178179D01*
X84561Y178166D01*
X84589Y178152D01*
X84617Y178096D01*
X84672Y178041D01*
X84741Y177971D01*
X84811Y177874D01*
X84880Y177777D01*
X84963Y177652D01*
X85102Y177389D01*
X85241Y177056D01*
X85296Y176890D01*
X85324Y176696D01*
X85352Y176501D01*
X85366Y176293D01*
Y176266D01*
Y176196D01*
X85352Y176085D01*
X85338Y175933D01*
X85310Y175766D01*
X85255Y175572D01*
X85199Y175364D01*
X85116Y175156D01*
X85102Y175128D01*
X85074Y175059D01*
X85019Y174948D01*
X84936Y174796D01*
X84825Y174629D01*
X84686Y174421D01*
X84520Y174213D01*
X84326Y173977D01*
X84298Y173950D01*
X84228Y173866D01*
X84159Y173797D01*
X84090Y173728D01*
X84007Y173645D01*
X83896Y173534D01*
X83785Y173423D01*
X83646Y173298D01*
X83507Y173159D01*
X83341Y173007D01*
X83160Y172854D01*
X82966Y172674D01*
X82745Y172493D01*
X82523Y172299D01*
X82509Y172285D01*
X82481Y172258D01*
X82425Y172216D01*
X82356Y172161D01*
X82273Y172077D01*
X82176Y171994D01*
X81954Y171814D01*
X81718Y171606D01*
X81496Y171398D01*
X81302Y171217D01*
X81219Y171148D01*
X81150Y171079D01*
X81136Y171065D01*
X81094Y171023D01*
X81039Y170968D01*
X80969Y170885D01*
X80900Y170788D01*
X80817Y170690D01*
X80650Y170455D01*
X85379D01*
Y169318D01*
X79014D01*
Y169331D01*
Y169387D01*
Y169470D01*
X79028Y169581D01*
X79042Y169706D01*
X79069Y169845D01*
X79097Y169983D01*
X79152Y170136D01*
Y170150D01*
X79166Y170163D01*
X79194Y170247D01*
X79250Y170372D01*
X79333Y170538D01*
X79444Y170732D01*
X79583Y170954D01*
X79735Y171176D01*
X79929Y171412D01*
Y171426D01*
X79957Y171439D01*
X80026Y171523D01*
X80151Y171647D01*
X80331Y171828D01*
X80539Y172036D01*
X80803Y172285D01*
X81122Y172563D01*
X81469Y172854D01*
X81482Y172868D01*
X81538Y172910D01*
X81621Y172979D01*
X81718Y173062D01*
X81843Y173173D01*
X81996Y173298D01*
X82148Y173437D01*
X82328Y173589D01*
X82675Y173922D01*
X83022Y174255D01*
X83188Y174421D01*
X83341Y174588D01*
X83479Y174740D01*
X83590Y174893D01*
Y174907D01*
X83618Y174920D01*
X83646Y174962D01*
X83674Y175018D01*
X83771Y175170D01*
X83882Y175350D01*
X83979Y175572D01*
X84076Y175808D01*
X84131Y176071D01*
X84159Y176321D01*
Y176335D01*
Y176349D01*
X84145Y176432D01*
X84131Y176571D01*
X84090Y176723D01*
X84034Y176917D01*
X83937Y177112D01*
X83812Y177306D01*
X83646Y177500D01*
X83618Y177528D01*
X83549Y177583D01*
X83452Y177652D01*
X83299Y177750D01*
X83105Y177833D01*
X82883Y177916D01*
X82620Y177971D01*
X82328Y177985D01*
X82245D01*
X82190Y177971D01*
X82023Y177958D01*
X81829Y177916D01*
X81621Y177861D01*
X81385Y177763D01*
X81164Y177639D01*
X80955Y177472D01*
X80928Y177444D01*
X80872Y177375D01*
X80789Y177264D01*
X80706Y177098D01*
X80609Y176904D01*
X80526Y176654D01*
X80470Y176377D01*
X80442Y176058D01*
X79236Y176182D01*
Y176196D01*
X79250Y176238D01*
Y176307D01*
X79264Y176404D01*
X79291Y176515D01*
X79319Y176640D01*
X79361Y176793D01*
X79402Y176945D01*
X79513Y177278D01*
X79679Y177611D01*
X79777Y177777D01*
X79901Y177944D01*
X80026Y178096D01*
X80165Y178235D01*
X80179Y178249D01*
X80206Y178263D01*
X80248Y178304D01*
X80317Y178346D01*
X80401Y178401D01*
X80498Y178457D01*
X80609Y178526D01*
X80747Y178596D01*
X80900Y178665D01*
X81066Y178734D01*
X81247Y178790D01*
X81441Y178845D01*
X81649Y178887D01*
X81871Y178928D01*
X82107Y178942D01*
X82356Y178956D01*
X82495D01*
X82592Y178942D01*
D02*
G37*
G36*
X335389Y411253D02*
X335542Y411239D01*
X335722Y411212D01*
X335916Y411170D01*
X336124Y411115D01*
X336318Y411031D01*
X336346Y411017D01*
X336401Y410990D01*
X336498Y410948D01*
X336609Y410879D01*
X336748Y410796D01*
X336873Y410685D01*
X336998Y410574D01*
X337109Y410435D01*
X337123Y410421D01*
X337150Y410366D01*
X337192Y410296D01*
X337261Y410199D01*
X337317Y410061D01*
X337372Y409922D01*
X337442Y409755D01*
X337483Y409575D01*
Y409561D01*
X337497Y409506D01*
X337511Y409422D01*
X337525Y409312D01*
Y409145D01*
X337539Y408951D01*
X337552Y408715D01*
Y408424D01*
Y404153D01*
X336374D01*
Y408369D01*
Y408382D01*
Y408396D01*
Y408493D01*
Y408618D01*
X336360Y408771D01*
X336346Y408951D01*
X336318Y409131D01*
X336277Y409298D01*
X336235Y409450D01*
Y409464D01*
X336207Y409506D01*
X336166Y409575D01*
X336124Y409658D01*
X336055Y409742D01*
X335971Y409839D01*
X335861Y409936D01*
X335736Y410019D01*
X335722Y410033D01*
X335680Y410061D01*
X335597Y410088D01*
X335500Y410130D01*
X335389Y410171D01*
X335250Y410213D01*
X335084Y410227D01*
X334917Y410241D01*
X334848D01*
X334793Y410227D01*
X334654Y410213D01*
X334474Y410185D01*
X334280Y410116D01*
X334058Y410033D01*
X333836Y409922D01*
X333628Y409755D01*
X333600Y409728D01*
X333545Y409658D01*
X333503Y409603D01*
X333461Y409534D01*
X333406Y409450D01*
X333364Y409353D01*
X333309Y409242D01*
X333253Y409104D01*
X333212Y408951D01*
X333170Y408785D01*
X333142Y408604D01*
X333115Y408410D01*
X333087Y408174D01*
Y407939D01*
Y404153D01*
X331908D01*
Y411115D01*
X332962D01*
Y410116D01*
X332976Y410130D01*
X333004Y410171D01*
X333045Y410227D01*
X333101Y410296D01*
X333184Y410379D01*
X333281Y410476D01*
X333392Y410588D01*
X333531Y410698D01*
X333669Y410796D01*
X333836Y410906D01*
X334016Y411003D01*
X334210Y411087D01*
X334432Y411156D01*
X334654Y411212D01*
X334904Y411253D01*
X335167Y411267D01*
X335278D01*
X335389Y411253D01*
D02*
G37*
G36*
X308582D02*
X308734Y411225D01*
X308914Y411170D01*
X309108Y411101D01*
X309330Y411003D01*
X309566Y410879D01*
X309136Y409797D01*
X309122Y409811D01*
X309067Y409839D01*
X308984Y409880D01*
X308873Y409922D01*
X308748Y409963D01*
X308595Y410005D01*
X308443Y410033D01*
X308290Y410047D01*
X308221D01*
X308151Y410033D01*
X308055Y410019D01*
X307957Y409991D01*
X307833Y409949D01*
X307708Y409894D01*
X307597Y409811D01*
X307583Y409797D01*
X307541Y409769D01*
X307500Y409714D01*
X307430Y409644D01*
X307361Y409547D01*
X307292Y409436D01*
X307222Y409312D01*
X307167Y409159D01*
X307153Y409131D01*
X307139Y409048D01*
X307111Y408923D01*
X307070Y408757D01*
X307028Y408549D01*
X307001Y408313D01*
X306987Y408063D01*
X306973Y407786D01*
Y404153D01*
X305794D01*
Y411115D01*
X306862D01*
Y410061D01*
X306876Y410074D01*
X306931Y410171D01*
X307001Y410296D01*
X307111Y410449D01*
X307222Y410601D01*
X307347Y410768D01*
X307472Y410906D01*
X307597Y411017D01*
X307611Y411031D01*
X307652Y411059D01*
X307736Y411101D01*
X307819Y411142D01*
X307930Y411184D01*
X308068Y411225D01*
X308207Y411253D01*
X308360Y411267D01*
X308457D01*
X308582Y411253D01*
D02*
G37*
G36*
X320744D02*
X320827D01*
X320938Y411239D01*
X321202Y411198D01*
X321493Y411128D01*
X321798Y411017D01*
X322103Y410879D01*
X322394Y410685D01*
X322408D01*
X322422Y410657D01*
X322505Y410574D01*
X322630Y410449D01*
X322783Y410269D01*
X322935Y410047D01*
X323088Y409769D01*
X323227Y409450D01*
X323324Y409076D01*
X322173Y408896D01*
Y408909D01*
X322159Y408923D01*
X322145Y409007D01*
X322103Y409131D01*
X322034Y409284D01*
X321964Y409450D01*
X321853Y409631D01*
X321729Y409797D01*
X321590Y409936D01*
X321576Y409949D01*
X321521Y409991D01*
X321424Y410047D01*
X321313Y410116D01*
X321160Y410185D01*
X320994Y410241D01*
X320799Y410282D01*
X320592Y410296D01*
X320508D01*
X320439Y410282D01*
X320286Y410269D01*
X320078Y410213D01*
X319856Y410144D01*
X319607Y410033D01*
X319371Y409866D01*
X319260Y409769D01*
X319149Y409658D01*
Y409644D01*
X319121Y409631D01*
X319094Y409589D01*
X319066Y409534D01*
X319024Y409464D01*
X318969Y409381D01*
X318927Y409284D01*
X318872Y409173D01*
X318816Y409034D01*
X318775Y408882D01*
X318719Y408715D01*
X318678Y408535D01*
X318650Y408341D01*
X318622Y408119D01*
X318594Y407883D01*
Y407634D01*
Y407620D01*
Y407578D01*
Y407495D01*
X318608Y407412D01*
Y407287D01*
X318622Y407162D01*
X318664Y406857D01*
X318719Y406524D01*
X318816Y406177D01*
X318941Y405872D01*
X319024Y405720D01*
X319121Y405595D01*
X319149Y405567D01*
X319219Y405498D01*
X319343Y405401D01*
X319496Y405290D01*
X319704Y405165D01*
X319940Y405068D01*
X320217Y404999D01*
X320370Y404985D01*
X320522Y404971D01*
X320550D01*
X320633Y404985D01*
X320772Y404999D01*
X320924Y405026D01*
X321105Y405068D01*
X321299Y405151D01*
X321493Y405248D01*
X321673Y405387D01*
X321701Y405401D01*
X321743Y405470D01*
X321826Y405567D01*
X321923Y405720D01*
X322020Y405900D01*
X322131Y406122D01*
X322214Y406399D01*
X322270Y406704D01*
X323434Y406552D01*
Y406538D01*
X323421Y406496D01*
X323407Y406441D01*
X323393Y406358D01*
X323365Y406247D01*
X323337Y406136D01*
X323240Y405858D01*
X323116Y405567D01*
X322935Y405248D01*
X322713Y404943D01*
X322589Y404804D01*
X322450Y404666D01*
X322436Y404652D01*
X322408Y404638D01*
X322367Y404610D01*
X322311Y404569D01*
X322242Y404513D01*
X322145Y404458D01*
X322034Y404402D01*
X321923Y404333D01*
X321646Y404208D01*
X321313Y404111D01*
X320952Y404028D01*
X320744Y404014D01*
X320536Y404000D01*
X320397D01*
X320300Y404014D01*
X320175Y404028D01*
X320037Y404055D01*
X319884Y404083D01*
X319718Y404111D01*
X319343Y404222D01*
X319163Y404305D01*
X318969Y404388D01*
X318775Y404499D01*
X318594Y404624D01*
X318414Y404763D01*
X318248Y404929D01*
X318234Y404943D01*
X318206Y404971D01*
X318165Y405026D01*
X318109Y405096D01*
X318054Y405193D01*
X317970Y405317D01*
X317901Y405456D01*
X317818Y405609D01*
X317735Y405789D01*
X317665Y405997D01*
X317582Y406205D01*
X317527Y406455D01*
X317471Y406704D01*
X317430Y406996D01*
X317402Y407287D01*
X317388Y407606D01*
Y407620D01*
Y407661D01*
Y407717D01*
Y407800D01*
X317402Y407897D01*
Y408008D01*
X317416Y408133D01*
X317430Y408271D01*
X317471Y408577D01*
X317540Y408909D01*
X317624Y409242D01*
X317749Y409575D01*
Y409589D01*
X317762Y409617D01*
X317790Y409658D01*
X317818Y409714D01*
X317901Y409866D01*
X318026Y410047D01*
X318192Y410255D01*
X318386Y410463D01*
X318622Y410671D01*
X318886Y410837D01*
X318899D01*
X318927Y410851D01*
X318969Y410879D01*
X319024Y410906D01*
X319094Y410934D01*
X319177Y410976D01*
X319385Y411059D01*
X319621Y411128D01*
X319912Y411198D01*
X320217Y411253D01*
X320550Y411267D01*
X320661D01*
X320744Y411253D01*
D02*
G37*
G36*
X313519D02*
X313727Y411239D01*
X313962Y411212D01*
X314198Y411170D01*
X314434Y411115D01*
X314656Y411045D01*
X314683Y411031D01*
X314753Y411003D01*
X314850Y410962D01*
X314975Y410906D01*
X315114Y410823D01*
X315252Y410740D01*
X315377Y410629D01*
X315488Y410518D01*
X315502Y410504D01*
X315529Y410463D01*
X315571Y410393D01*
X315627Y410310D01*
X315696Y410185D01*
X315751Y410061D01*
X315807Y409908D01*
X315849Y409728D01*
Y409714D01*
X315862Y409672D01*
X315876Y409589D01*
X315890Y409478D01*
Y409325D01*
X315904Y409145D01*
X315918Y408909D01*
Y408646D01*
Y407065D01*
Y407051D01*
Y406996D01*
Y406912D01*
Y406801D01*
Y406677D01*
Y406524D01*
X315932Y406191D01*
Y405844D01*
X315946Y405498D01*
X315959Y405345D01*
Y405207D01*
X315973Y405082D01*
X315987Y404985D01*
Y404971D01*
X316001Y404915D01*
X316015Y404832D01*
X316056Y404721D01*
X316084Y404596D01*
X316140Y404458D01*
X316209Y404305D01*
X316278Y404153D01*
X315044D01*
X315030Y404166D01*
X315016Y404222D01*
X314989Y404291D01*
X314947Y404402D01*
X314905Y404527D01*
X314878Y404680D01*
X314850Y404846D01*
X314822Y405026D01*
X314808D01*
X314795Y404999D01*
X314711Y404929D01*
X314587Y404832D01*
X314420Y404707D01*
X314212Y404582D01*
X314004Y404444D01*
X313782Y404319D01*
X313546Y404222D01*
X313519Y404208D01*
X313435Y404194D01*
X313311Y404153D01*
X313158Y404111D01*
X312964Y404069D01*
X312742Y404042D01*
X312492Y404014D01*
X312243Y404000D01*
X312132D01*
X312049Y404014D01*
X311952D01*
X311840Y404028D01*
X311591Y404069D01*
X311313Y404139D01*
X311008Y404236D01*
X310731Y404375D01*
X310481Y404555D01*
X310454Y404582D01*
X310384Y404652D01*
X310287Y404777D01*
X310176Y404943D01*
X310065Y405151D01*
X309968Y405387D01*
X309899Y405678D01*
X309885Y405817D01*
X309871Y405983D01*
Y406011D01*
Y406066D01*
X309885Y406163D01*
X309899Y406288D01*
X309927Y406441D01*
X309968Y406593D01*
X310024Y406760D01*
X310093Y406912D01*
X310107Y406926D01*
X310135Y406982D01*
X310190Y407065D01*
X310259Y407162D01*
X310343Y407273D01*
X310454Y407384D01*
X310565Y407495D01*
X310703Y407592D01*
X310717Y407606D01*
X310773Y407634D01*
X310842Y407689D01*
X310953Y407744D01*
X311078Y407800D01*
X311230Y407869D01*
X311383Y407925D01*
X311563Y407980D01*
X311577D01*
X311632Y407994D01*
X311716Y408022D01*
X311827Y408036D01*
X311965Y408063D01*
X312146Y408091D01*
X312354Y408133D01*
X312603Y408161D01*
X312617D01*
X312673Y408174D01*
X312742D01*
X312839Y408188D01*
X312950Y408202D01*
X313089Y408230D01*
X313241Y408244D01*
X313408Y408271D01*
X313741Y408341D01*
X314101Y408410D01*
X314420Y408493D01*
X314573Y408535D01*
X314711Y408577D01*
Y408590D01*
Y408618D01*
X314725Y408701D01*
Y408798D01*
Y408854D01*
Y408882D01*
Y408896D01*
Y408909D01*
Y408993D01*
X314711Y409131D01*
X314683Y409284D01*
X314642Y409450D01*
X314573Y409617D01*
X314489Y409769D01*
X314378Y409894D01*
X314365Y409908D01*
X314295Y409963D01*
X314184Y410019D01*
X314046Y410102D01*
X313851Y410171D01*
X313629Y410241D01*
X313352Y410282D01*
X313033Y410296D01*
X312894D01*
X312756Y410282D01*
X312562Y410255D01*
X312367Y410227D01*
X312160Y410171D01*
X311965Y410102D01*
X311799Y410005D01*
X311785Y409991D01*
X311730Y409949D01*
X311660Y409880D01*
X311577Y409769D01*
X311494Y409631D01*
X311397Y409450D01*
X311313Y409228D01*
X311230Y408979D01*
X310079Y409131D01*
Y409145D01*
X310093Y409159D01*
Y409201D01*
X310107Y409256D01*
X310149Y409381D01*
X310204Y409561D01*
X310273Y409742D01*
X310357Y409936D01*
X310468Y410130D01*
X310592Y410310D01*
X310606Y410324D01*
X310662Y410379D01*
X310745Y410463D01*
X310856Y410574D01*
X311008Y410685D01*
X311189Y410796D01*
X311397Y410920D01*
X311632Y411017D01*
X311646D01*
X311660Y411031D01*
X311702Y411045D01*
X311757Y411059D01*
X311896Y411101D01*
X312090Y411142D01*
X312312Y411184D01*
X312589Y411225D01*
X312881Y411253D01*
X313214Y411267D01*
X313366D01*
X313519Y411253D01*
D02*
G37*
G36*
X297473Y404153D02*
X296031D01*
X294907Y407065D01*
X290885D01*
X289845Y404153D01*
X288500D01*
X292161Y413750D01*
X293548D01*
X297473Y404153D01*
D02*
G37*
G36*
X327498Y411253D02*
X327623Y411239D01*
X327761Y411212D01*
X327914Y411184D01*
X328094Y411156D01*
X328469Y411031D01*
X328663Y410962D01*
X328857Y410865D01*
X329051Y410768D01*
X329245Y410629D01*
X329426Y410490D01*
X329606Y410324D01*
X329620Y410310D01*
X329647Y410282D01*
X329689Y410227D01*
X329745Y410158D01*
X329814Y410061D01*
X329897Y409936D01*
X329980Y409797D01*
X330064Y409644D01*
X330147Y409478D01*
X330230Y409270D01*
X330313Y409062D01*
X330383Y408826D01*
X330438Y408577D01*
X330480Y408313D01*
X330507Y408036D01*
X330521Y407731D01*
Y407717D01*
Y407675D01*
Y407606D01*
Y407509D01*
X330507Y407398D01*
X330494Y407259D01*
Y407120D01*
X330466Y406968D01*
X330424Y406621D01*
X330341Y406274D01*
X330244Y405928D01*
X330105Y405609D01*
Y405595D01*
X330091Y405581D01*
X330064Y405539D01*
X330036Y405484D01*
X329939Y405345D01*
X329814Y405179D01*
X329647Y404985D01*
X329440Y404790D01*
X329204Y404596D01*
X328926Y404416D01*
X328913D01*
X328899Y404402D01*
X328857Y404375D01*
X328788Y404347D01*
X328718Y404319D01*
X328635Y404291D01*
X328427Y404208D01*
X328191Y404139D01*
X327900Y404069D01*
X327595Y404014D01*
X327262Y404000D01*
X327123D01*
X327013Y404014D01*
X326888Y404028D01*
X326749Y404055D01*
X326583Y404083D01*
X326416Y404111D01*
X326042Y404222D01*
X325834Y404305D01*
X325640Y404388D01*
X325445Y404499D01*
X325251Y404624D01*
X325071Y404763D01*
X324891Y404929D01*
X324877Y404943D01*
X324849Y404971D01*
X324808Y405026D01*
X324752Y405109D01*
X324683Y405207D01*
X324613Y405317D01*
X324530Y405456D01*
X324447Y405623D01*
X324364Y405803D01*
X324281Y406011D01*
X324211Y406233D01*
X324142Y406469D01*
X324086Y406732D01*
X324045Y407009D01*
X324017Y407315D01*
X324003Y407634D01*
Y407661D01*
Y407717D01*
X324017Y407814D01*
Y407952D01*
X324031Y408105D01*
X324059Y408299D01*
X324086Y408493D01*
X324142Y408715D01*
X324197Y408937D01*
X324267Y409173D01*
X324350Y409422D01*
X324461Y409658D01*
X324572Y409880D01*
X324724Y410102D01*
X324877Y410310D01*
X325071Y410490D01*
X325085Y410504D01*
X325113Y410518D01*
X325168Y410560D01*
X325237Y410615D01*
X325321Y410671D01*
X325432Y410740D01*
X325542Y410809D01*
X325681Y410879D01*
X325834Y410948D01*
X326000Y411017D01*
X326375Y411142D01*
X326805Y411239D01*
X327026Y411253D01*
X327262Y411267D01*
X327401D01*
X327498Y411253D01*
D02*
G37*
G36*
X299498Y410324D02*
X299512Y410338D01*
X299525Y410366D01*
X299567Y410407D01*
X299636Y410476D01*
X299706Y410546D01*
X299789Y410629D01*
X299900Y410712D01*
X300011Y410796D01*
X300288Y410976D01*
X300607Y411115D01*
X300787Y411184D01*
X300982Y411225D01*
X301190Y411253D01*
X301398Y411267D01*
X301509D01*
X301633Y411253D01*
X301786Y411239D01*
X301966Y411198D01*
X302174Y411156D01*
X302396Y411087D01*
X302604Y411003D01*
X302632Y410990D01*
X302701Y410962D01*
X302812Y410893D01*
X302937Y410809D01*
X303090Y410712D01*
X303242Y410588D01*
X303409Y410435D01*
X303547Y410269D01*
X303561Y410255D01*
X303603Y410185D01*
X303672Y410088D01*
X303755Y409963D01*
X303852Y409797D01*
X303949Y409603D01*
X304046Y409381D01*
X304130Y409145D01*
Y409131D01*
X304144Y409117D01*
X304157Y409076D01*
X304171Y409034D01*
X304199Y408896D01*
X304241Y408715D01*
X304282Y408507D01*
X304324Y408271D01*
X304338Y408008D01*
X304352Y407731D01*
Y407717D01*
Y407647D01*
Y407564D01*
X304338Y407439D01*
X304324Y407287D01*
X304310Y407120D01*
X304282Y406926D01*
X304241Y406718D01*
X304130Y406274D01*
X304060Y406039D01*
X303977Y405817D01*
X303880Y405581D01*
X303755Y405373D01*
X303617Y405165D01*
X303464Y404971D01*
X303450Y404957D01*
X303422Y404929D01*
X303381Y404888D01*
X303312Y404818D01*
X303214Y404749D01*
X303117Y404666D01*
X303006Y404582D01*
X302868Y404485D01*
X302715Y404402D01*
X302563Y404305D01*
X302188Y404153D01*
X301994Y404083D01*
X301786Y404042D01*
X301564Y404014D01*
X301342Y404000D01*
X301287D01*
X301217Y404014D01*
X301134D01*
X301037Y404028D01*
X300912Y404055D01*
X300635Y404125D01*
X300482Y404180D01*
X300330Y404250D01*
X300163Y404333D01*
X300011Y404430D01*
X299844Y404555D01*
X299692Y404693D01*
X299553Y404846D01*
X299414Y405026D01*
Y404153D01*
X298319D01*
Y413750D01*
X299498D01*
Y410324D01*
D02*
G37*
G36*
X381379Y351003D02*
X381532Y350989D01*
X381712Y350962D01*
X381906Y350920D01*
X382114Y350864D01*
X382309Y350781D01*
X382336Y350767D01*
X382392Y350740D01*
X382489Y350698D01*
X382600Y350629D01*
X382738Y350546D01*
X382863Y350435D01*
X382988Y350324D01*
X383099Y350185D01*
X383113Y350171D01*
X383141Y350116D01*
X383182Y350046D01*
X383252Y349949D01*
X383307Y349810D01*
X383363Y349672D01*
X383432Y349505D01*
X383474Y349325D01*
Y349311D01*
X383487Y349256D01*
X383501Y349173D01*
X383515Y349062D01*
Y348895D01*
X383529Y348701D01*
X383543Y348465D01*
Y348174D01*
Y343903D01*
X382364D01*
Y348119D01*
Y348132D01*
Y348146D01*
Y348243D01*
Y348368D01*
X382350Y348521D01*
X382336Y348701D01*
X382309Y348881D01*
X382267Y349048D01*
X382225Y349200D01*
Y349214D01*
X382198Y349256D01*
X382156Y349325D01*
X382114Y349408D01*
X382045Y349492D01*
X381962Y349589D01*
X381851Y349686D01*
X381726Y349769D01*
X381712Y349783D01*
X381671Y349810D01*
X381587Y349838D01*
X381490Y349880D01*
X381379Y349921D01*
X381241Y349963D01*
X381074Y349977D01*
X380908Y349991D01*
X380839D01*
X380783Y349977D01*
X380644Y349963D01*
X380464Y349935D01*
X380270Y349866D01*
X380048Y349783D01*
X379826Y349672D01*
X379618Y349505D01*
X379590Y349478D01*
X379535Y349408D01*
X379493Y349353D01*
X379452Y349283D01*
X379396Y349200D01*
X379355Y349103D01*
X379299Y348992D01*
X379244Y348854D01*
X379202Y348701D01*
X379160Y348535D01*
X379133Y348354D01*
X379105Y348160D01*
X379077Y347924D01*
Y347689D01*
Y343903D01*
X377898D01*
Y350864D01*
X378952D01*
Y349866D01*
X378966Y349880D01*
X378994Y349921D01*
X379036Y349977D01*
X379091Y350046D01*
X379174Y350130D01*
X379271Y350227D01*
X379382Y350337D01*
X379521Y350448D01*
X379660Y350546D01*
X379826Y350657D01*
X380006Y350754D01*
X380201Y350837D01*
X380423Y350906D01*
X380644Y350962D01*
X380894Y351003D01*
X381157Y351017D01*
X381269D01*
X381379Y351003D01*
D02*
G37*
G36*
X364904Y348022D02*
X367691Y350864D01*
X369231D01*
X366554Y348271D01*
X369494Y343903D01*
X368038D01*
X365722Y347453D01*
X364904Y346662D01*
Y343903D01*
X363725D01*
Y353499D01*
X364904D01*
Y348022D01*
D02*
G37*
G36*
X359509Y351003D02*
X359717Y350989D01*
X359953Y350962D01*
X360188Y350920D01*
X360424Y350864D01*
X360646Y350795D01*
X360674Y350781D01*
X360743Y350754D01*
X360840Y350712D01*
X360965Y350657D01*
X361104Y350573D01*
X361242Y350490D01*
X361367Y350379D01*
X361478Y350268D01*
X361492Y350254D01*
X361520Y350213D01*
X361562Y350143D01*
X361617Y350060D01*
X361686Y349935D01*
X361742Y349810D01*
X361797Y349658D01*
X361839Y349478D01*
Y349464D01*
X361853Y349422D01*
X361867Y349339D01*
X361880Y349228D01*
Y349076D01*
X361894Y348895D01*
X361908Y348659D01*
Y348396D01*
Y346815D01*
Y346801D01*
Y346746D01*
Y346662D01*
Y346551D01*
Y346427D01*
Y346274D01*
X361922Y345941D01*
Y345594D01*
X361936Y345248D01*
X361950Y345095D01*
Y344957D01*
X361964Y344832D01*
X361978Y344735D01*
Y344721D01*
X361991Y344665D01*
X362005Y344582D01*
X362047Y344471D01*
X362075Y344346D01*
X362130Y344208D01*
X362199Y344055D01*
X362269Y343903D01*
X361035D01*
X361021Y343916D01*
X361007Y343972D01*
X360979Y344041D01*
X360937Y344152D01*
X360896Y344277D01*
X360868Y344430D01*
X360840Y344596D01*
X360813Y344776D01*
X360799D01*
X360785Y344748D01*
X360702Y344679D01*
X360577Y344582D01*
X360410Y344457D01*
X360202Y344333D01*
X359994Y344194D01*
X359772Y344069D01*
X359537Y343972D01*
X359509Y343958D01*
X359426Y343944D01*
X359301Y343903D01*
X359148Y343861D01*
X358954Y343819D01*
X358732Y343792D01*
X358483Y343764D01*
X358233Y343750D01*
X358122D01*
X358039Y343764D01*
X357942D01*
X357831Y343778D01*
X357581Y343819D01*
X357304Y343889D01*
X356999Y343986D01*
X356721Y344124D01*
X356472Y344305D01*
X356444Y344333D01*
X356375Y344402D01*
X356278Y344527D01*
X356167Y344693D01*
X356056Y344901D01*
X355959Y345137D01*
X355889Y345428D01*
X355875Y345567D01*
X355862Y345733D01*
Y345761D01*
Y345816D01*
X355875Y345914D01*
X355889Y346038D01*
X355917Y346191D01*
X355959Y346343D01*
X356014Y346510D01*
X356083Y346662D01*
X356097Y346676D01*
X356125Y346732D01*
X356180Y346815D01*
X356250Y346912D01*
X356333Y347023D01*
X356444Y347134D01*
X356555Y347245D01*
X356694Y347342D01*
X356707Y347356D01*
X356763Y347383D01*
X356832Y347439D01*
X356943Y347495D01*
X357068Y347550D01*
X357221Y347619D01*
X357373Y347675D01*
X357553Y347730D01*
X357567D01*
X357623Y347744D01*
X357706Y347772D01*
X357817Y347786D01*
X357956Y347813D01*
X358136Y347841D01*
X358344Y347883D01*
X358594Y347910D01*
X358607D01*
X358663Y347924D01*
X358732D01*
X358829Y347938D01*
X358940Y347952D01*
X359079Y347980D01*
X359232Y347994D01*
X359398Y348022D01*
X359731Y348091D01*
X360091Y348160D01*
X360410Y348243D01*
X360563Y348285D01*
X360702Y348327D01*
Y348340D01*
Y348368D01*
X360715Y348451D01*
Y348549D01*
Y348604D01*
Y348632D01*
Y348646D01*
Y348659D01*
Y348743D01*
X360702Y348881D01*
X360674Y349034D01*
X360632Y349200D01*
X360563Y349367D01*
X360480Y349519D01*
X360369Y349644D01*
X360355Y349658D01*
X360286Y349713D01*
X360175Y349769D01*
X360036Y349852D01*
X359842Y349921D01*
X359620Y349991D01*
X359342Y350032D01*
X359024Y350046D01*
X358885D01*
X358746Y350032D01*
X358552Y350005D01*
X358358Y349977D01*
X358150Y349921D01*
X357956Y349852D01*
X357789Y349755D01*
X357775Y349741D01*
X357720Y349700D01*
X357651Y349630D01*
X357567Y349519D01*
X357484Y349381D01*
X357387Y349200D01*
X357304Y348978D01*
X357221Y348729D01*
X356070Y348881D01*
Y348895D01*
X356083Y348909D01*
Y348951D01*
X356097Y349006D01*
X356139Y349131D01*
X356194Y349311D01*
X356264Y349492D01*
X356347Y349686D01*
X356458Y349880D01*
X356583Y350060D01*
X356597Y350074D01*
X356652Y350130D01*
X356735Y350213D01*
X356846Y350324D01*
X356999Y350435D01*
X357179Y350546D01*
X357387Y350670D01*
X357623Y350767D01*
X357637D01*
X357651Y350781D01*
X357692Y350795D01*
X357748Y350809D01*
X357886Y350851D01*
X358080Y350892D01*
X358302Y350934D01*
X358580Y350975D01*
X358871Y351003D01*
X359204Y351017D01*
X359356D01*
X359509Y351003D01*
D02*
G37*
G36*
X351313Y353486D02*
X351437D01*
X351729Y353472D01*
X352034Y353430D01*
X352367Y353388D01*
X352672Y353319D01*
X352824Y353278D01*
X352949Y353236D01*
X352963D01*
X352977Y353222D01*
X353060Y353181D01*
X353185Y353125D01*
X353338Y353028D01*
X353504Y352903D01*
X353684Y352737D01*
X353851Y352543D01*
X354017Y352321D01*
Y352307D01*
X354031Y352293D01*
X354086Y352210D01*
X354142Y352071D01*
X354225Y351891D01*
X354294Y351683D01*
X354364Y351433D01*
X354405Y351170D01*
X354419Y350878D01*
Y350864D01*
Y350837D01*
Y350781D01*
X354405Y350712D01*
Y350615D01*
X354392Y350518D01*
X354336Y350282D01*
X354253Y350005D01*
X354142Y349713D01*
X353975Y349422D01*
X353865Y349283D01*
X353754Y349145D01*
X353740Y349131D01*
X353726Y349117D01*
X353684Y349076D01*
X353629Y349034D01*
X353559Y348978D01*
X353476Y348923D01*
X353365Y348854D01*
X353254Y348770D01*
X353116Y348701D01*
X352963Y348632D01*
X352797Y348549D01*
X352616Y348479D01*
X352408Y348424D01*
X352200Y348354D01*
X351964Y348313D01*
X351715Y348271D01*
X351743Y348257D01*
X351798Y348229D01*
X351881Y348174D01*
X351992Y348119D01*
X352242Y347966D01*
X352367Y347869D01*
X352478Y347786D01*
X352505Y347758D01*
X352575Y347689D01*
X352686Y347578D01*
X352824Y347439D01*
X352977Y347245D01*
X353157Y347037D01*
X353338Y346787D01*
X353532Y346510D01*
X355182Y343903D01*
X353601D01*
X352339Y345900D01*
Y345914D01*
X352311Y345941D01*
X352284Y345983D01*
X352242Y346038D01*
X352145Y346191D01*
X352020Y346385D01*
X351867Y346593D01*
X351715Y346815D01*
X351562Y347023D01*
X351424Y347217D01*
X351410Y347231D01*
X351368Y347286D01*
X351299Y347370D01*
X351202Y347467D01*
X350994Y347675D01*
X350883Y347772D01*
X350772Y347855D01*
X350758Y347869D01*
X350730Y347883D01*
X350675Y347910D01*
X350592Y347952D01*
X350508Y347994D01*
X350411Y348035D01*
X350189Y348105D01*
X350176D01*
X350148Y348119D01*
X350092D01*
X350023Y348132D01*
X349926Y348146D01*
X349815D01*
X349662Y348160D01*
X348026D01*
Y343903D01*
X346750D01*
Y353499D01*
X351202D01*
X351313Y353486D01*
D02*
G37*
G36*
X373488Y351003D02*
X373613Y350989D01*
X373752Y350962D01*
X373904Y350934D01*
X374085Y350906D01*
X374459Y350781D01*
X374653Y350712D01*
X374847Y350615D01*
X375042Y350518D01*
X375236Y350379D01*
X375416Y350240D01*
X375596Y350074D01*
X375610Y350060D01*
X375638Y350032D01*
X375680Y349977D01*
X375735Y349908D01*
X375804Y349810D01*
X375887Y349686D01*
X375971Y349547D01*
X376054Y349394D01*
X376137Y349228D01*
X376220Y349020D01*
X376304Y348812D01*
X376373Y348576D01*
X376428Y348327D01*
X376470Y348063D01*
X376498Y347786D01*
X376512Y347481D01*
Y347467D01*
Y347425D01*
Y347356D01*
Y347259D01*
X376498Y347148D01*
X376484Y347009D01*
Y346870D01*
X376456Y346718D01*
X376414Y346371D01*
X376331Y346024D01*
X376234Y345678D01*
X376096Y345359D01*
Y345345D01*
X376082Y345331D01*
X376054Y345289D01*
X376026Y345234D01*
X375929Y345095D01*
X375804Y344929D01*
X375638Y344735D01*
X375430Y344540D01*
X375194Y344346D01*
X374917Y344166D01*
X374903D01*
X374889Y344152D01*
X374847Y344124D01*
X374778Y344097D01*
X374709Y344069D01*
X374626Y344041D01*
X374417Y343958D01*
X374182Y343889D01*
X373890Y343819D01*
X373585Y343764D01*
X373252Y343750D01*
X373114D01*
X373003Y343764D01*
X372878Y343778D01*
X372739Y343806D01*
X372573Y343833D01*
X372407Y343861D01*
X372032Y343972D01*
X371824Y344055D01*
X371630Y344138D01*
X371436Y344249D01*
X371242Y344374D01*
X371061Y344513D01*
X370881Y344679D01*
X370867Y344693D01*
X370839Y344721D01*
X370798Y344776D01*
X370742Y344860D01*
X370673Y344957D01*
X370604Y345067D01*
X370520Y345206D01*
X370437Y345373D01*
X370354Y345553D01*
X370271Y345761D01*
X370201Y345983D01*
X370132Y346219D01*
X370077Y346482D01*
X370035Y346759D01*
X370007Y347065D01*
X369993Y347383D01*
Y347411D01*
Y347467D01*
X370007Y347564D01*
Y347702D01*
X370021Y347855D01*
X370049Y348049D01*
X370077Y348243D01*
X370132Y348465D01*
X370188Y348687D01*
X370257Y348923D01*
X370340Y349173D01*
X370451Y349408D01*
X370562Y349630D01*
X370715Y349852D01*
X370867Y350060D01*
X371061Y350240D01*
X371075Y350254D01*
X371103Y350268D01*
X371158Y350310D01*
X371228Y350365D01*
X371311Y350421D01*
X371422Y350490D01*
X371533Y350559D01*
X371671Y350629D01*
X371824Y350698D01*
X371991Y350767D01*
X372365Y350892D01*
X372795Y350989D01*
X373017Y351003D01*
X373252Y351017D01*
X373391D01*
X373488Y351003D01*
D02*
G37*
G36*
X216329Y377918D02*
X215150D01*
Y379263D01*
X216329D01*
Y377918D01*
D02*
G37*
G36*
X205151D02*
X203972D01*
Y379263D01*
X205151D01*
Y377918D01*
D02*
G37*
G36*
X198758Y379416D02*
X198855D01*
X199119Y379388D01*
X199410Y379347D01*
X199715Y379277D01*
X200048Y379194D01*
X200353Y379083D01*
X200367D01*
X200394Y379069D01*
X200436Y379041D01*
X200492Y379014D01*
X200630Y378944D01*
X200811Y378820D01*
X201019Y378681D01*
X201227Y378501D01*
X201421Y378293D01*
X201601Y378057D01*
Y378043D01*
X201615Y378029D01*
X201643Y377988D01*
X201670Y377946D01*
X201740Y377807D01*
X201823Y377627D01*
X201920Y377405D01*
X201989Y377141D01*
X202059Y376864D01*
X202086Y376559D01*
X200866Y376462D01*
Y376476D01*
Y376503D01*
X200852Y376545D01*
X200838Y376614D01*
X200797Y376767D01*
X200741Y376975D01*
X200658Y377197D01*
X200533Y377419D01*
X200381Y377627D01*
X200186Y377821D01*
X200159Y377835D01*
X200089Y377890D01*
X199951Y377974D01*
X199770Y378057D01*
X199535Y378140D01*
X199257Y378223D01*
X198911Y378279D01*
X198522Y378293D01*
X198328D01*
X198245Y378279D01*
X198134Y378265D01*
X197884Y378237D01*
X197607Y378182D01*
X197330Y378112D01*
X197066Y378001D01*
X196955Y377932D01*
X196844Y377863D01*
X196816Y377849D01*
X196761Y377793D01*
X196678Y377696D01*
X196595Y377585D01*
X196497Y377433D01*
X196414Y377266D01*
X196359Y377072D01*
X196331Y376850D01*
Y376823D01*
Y376767D01*
X196345Y376670D01*
X196373Y376559D01*
X196414Y376420D01*
X196484Y376282D01*
X196567Y376143D01*
X196692Y376004D01*
X196705Y375990D01*
X196775Y375949D01*
X196830Y375907D01*
X196886Y375880D01*
X196969Y375838D01*
X197066Y375782D01*
X197191Y375741D01*
X197330Y375685D01*
X197482Y375630D01*
X197662Y375560D01*
X197857Y375505D01*
X198078Y375436D01*
X198328Y375380D01*
X198605Y375311D01*
X198619D01*
X198675Y375297D01*
X198758Y375283D01*
X198855Y375255D01*
X198980Y375228D01*
X199132Y375186D01*
X199285Y375144D01*
X199451Y375103D01*
X199812Y375006D01*
X200159Y374909D01*
X200325Y374853D01*
X200478Y374798D01*
X200616Y374756D01*
X200727Y374701D01*
X200741D01*
X200769Y374687D01*
X200811Y374659D01*
X200866Y374631D01*
X201019Y374548D01*
X201199Y374437D01*
X201407Y374285D01*
X201615Y374118D01*
X201809Y373924D01*
X201975Y373716D01*
X201989Y373688D01*
X202045Y373619D01*
X202100Y373494D01*
X202183Y373328D01*
X202253Y373134D01*
X202322Y372898D01*
X202364Y372634D01*
X202378Y372357D01*
Y372343D01*
Y372329D01*
Y372287D01*
Y372232D01*
X202350Y372080D01*
X202322Y371885D01*
X202267Y371664D01*
X202197Y371428D01*
X202086Y371178D01*
X201934Y370915D01*
Y370901D01*
X201920Y370887D01*
X201851Y370804D01*
X201754Y370679D01*
X201615Y370540D01*
X201435Y370374D01*
X201213Y370193D01*
X200963Y370027D01*
X200672Y369874D01*
X200658D01*
X200630Y369861D01*
X200589Y369847D01*
X200533Y369819D01*
X200450Y369791D01*
X200353Y369750D01*
X200131Y369694D01*
X199867Y369625D01*
X199548Y369556D01*
X199202Y369514D01*
X198827Y369500D01*
X198605D01*
X198494Y369514D01*
X198370D01*
X198231Y369528D01*
X198065Y369542D01*
X197718Y369597D01*
X197357Y369652D01*
X196997Y369750D01*
X196650Y369874D01*
X196636D01*
X196608Y369888D01*
X196567Y369916D01*
X196511Y369944D01*
X196345Y370027D01*
X196151Y370152D01*
X195929Y370318D01*
X195693Y370512D01*
X195471Y370748D01*
X195263Y371012D01*
Y371026D01*
X195235Y371053D01*
X195222Y371095D01*
X195180Y371150D01*
X195152Y371220D01*
X195111Y371303D01*
X195014Y371511D01*
X194916Y371774D01*
X194833Y372066D01*
X194778Y372398D01*
X194750Y372745D01*
X195943Y372856D01*
Y372842D01*
Y372828D01*
X195957Y372787D01*
Y372731D01*
X195984Y372607D01*
X196026Y372426D01*
X196081Y372246D01*
X196137Y372038D01*
X196234Y371844D01*
X196331Y371664D01*
X196345Y371650D01*
X196387Y371594D01*
X196456Y371497D01*
X196567Y371400D01*
X196705Y371275D01*
X196858Y371150D01*
X197066Y371026D01*
X197288Y370915D01*
X197302D01*
X197316Y370901D01*
X197357Y370887D01*
X197399Y370873D01*
X197538Y370831D01*
X197718Y370776D01*
X197940Y370720D01*
X198189Y370679D01*
X198467Y370651D01*
X198772Y370637D01*
X198897D01*
X199035Y370651D01*
X199202Y370665D01*
X199396Y370693D01*
X199618Y370720D01*
X199840Y370776D01*
X200048Y370845D01*
X200075Y370859D01*
X200145Y370887D01*
X200242Y370942D01*
X200367Y370998D01*
X200492Y371095D01*
X200630Y371192D01*
X200769Y371303D01*
X200880Y371442D01*
X200894Y371455D01*
X200921Y371511D01*
X200963Y371580D01*
X201019Y371691D01*
X201074Y371802D01*
X201116Y371941D01*
X201143Y372093D01*
X201157Y372260D01*
Y372274D01*
Y372343D01*
X201143Y372426D01*
X201129Y372537D01*
X201088Y372648D01*
X201046Y372787D01*
X200977Y372925D01*
X200880Y373050D01*
X200866Y373064D01*
X200824Y373106D01*
X200769Y373161D01*
X200672Y373245D01*
X200561Y373328D01*
X200408Y373425D01*
X200228Y373522D01*
X200020Y373605D01*
X200006Y373619D01*
X199937Y373633D01*
X199826Y373674D01*
X199757Y373688D01*
X199659Y373716D01*
X199562Y373758D01*
X199438Y373785D01*
X199299Y373827D01*
X199132Y373868D01*
X198966Y373910D01*
X198772Y373966D01*
X198550Y374021D01*
X198314Y374077D01*
X198300D01*
X198259Y374090D01*
X198189Y374104D01*
X198106Y374132D01*
X197995Y374160D01*
X197870Y374188D01*
X197593Y374271D01*
X197288Y374368D01*
X196969Y374465D01*
X196692Y374562D01*
X196567Y374617D01*
X196456Y374673D01*
X196442D01*
X196428Y374687D01*
X196345Y374742D01*
X196220Y374812D01*
X196081Y374922D01*
X195915Y375047D01*
X195749Y375200D01*
X195582Y375380D01*
X195443Y375574D01*
X195430Y375602D01*
X195388Y375671D01*
X195333Y375782D01*
X195277Y375921D01*
X195222Y376101D01*
X195166Y376309D01*
X195124Y376531D01*
X195111Y376767D01*
Y376781D01*
Y376795D01*
Y376836D01*
Y376892D01*
X195138Y377030D01*
X195166Y377211D01*
X195208Y377419D01*
X195277Y377655D01*
X195374Y377890D01*
X195513Y378126D01*
Y378140D01*
X195527Y378154D01*
X195596Y378237D01*
X195693Y378348D01*
X195818Y378487D01*
X195984Y378639D01*
X196192Y378806D01*
X196442Y378958D01*
X196719Y379097D01*
X196733D01*
X196761Y379111D01*
X196803Y379125D01*
X196858Y379152D01*
X196927Y379180D01*
X197024Y379208D01*
X197232Y379263D01*
X197496Y379319D01*
X197801Y379374D01*
X198120Y379416D01*
X198481Y379430D01*
X198661D01*
X198758Y379416D01*
D02*
G37*
G36*
X225579Y376767D02*
X225676D01*
X225774Y376753D01*
X226009Y376712D01*
X226259Y376642D01*
X226523Y376531D01*
X226786Y376393D01*
X227008Y376198D01*
X227036Y376171D01*
X227091Y376087D01*
X227188Y375963D01*
X227230Y375866D01*
X227285Y375769D01*
X227341Y375644D01*
X227382Y375519D01*
X227438Y375380D01*
X227479Y375214D01*
X227507Y375047D01*
X227535Y374853D01*
X227563Y374659D01*
Y374437D01*
Y369666D01*
X226384D01*
Y374035D01*
Y374049D01*
Y374063D01*
Y374146D01*
Y374271D01*
X226370Y374423D01*
X226356Y374590D01*
X226342Y374756D01*
X226315Y374922D01*
X226273Y375047D01*
Y375061D01*
X226245Y375103D01*
X226217Y375158D01*
X226176Y375228D01*
X226120Y375311D01*
X226051Y375394D01*
X225968Y375477D01*
X225857Y375560D01*
X225843Y375574D01*
X225801Y375588D01*
X225746Y375616D01*
X225649Y375658D01*
X225552Y375699D01*
X225427Y375727D01*
X225302Y375741D01*
X225149Y375755D01*
X225080D01*
X225025Y375741D01*
X224886Y375727D01*
X224720Y375699D01*
X224526Y375630D01*
X224317Y375547D01*
X224109Y375422D01*
X223915Y375255D01*
X223901Y375228D01*
X223846Y375158D01*
X223763Y375047D01*
X223680Y374881D01*
X223582Y374659D01*
X223513Y374395D01*
X223458Y374077D01*
X223430Y373702D01*
Y369666D01*
X222251D01*
Y374174D01*
Y374188D01*
Y374215D01*
Y374243D01*
Y374299D01*
X222237Y374451D01*
X222209Y374617D01*
X222182Y374812D01*
X222126Y375006D01*
X222057Y375186D01*
X221960Y375353D01*
X221946Y375366D01*
X221904Y375422D01*
X221835Y375477D01*
X221738Y375560D01*
X221613Y375630D01*
X221447Y375699D01*
X221252Y375741D01*
X221017Y375755D01*
X220933D01*
X220837Y375741D01*
X220725Y375727D01*
X220587Y375685D01*
X220420Y375644D01*
X220268Y375574D01*
X220101Y375491D01*
X220088Y375477D01*
X220032Y375436D01*
X219963Y375380D01*
X219866Y375297D01*
X219769Y375186D01*
X219671Y375047D01*
X219574Y374895D01*
X219491Y374715D01*
X219477Y374687D01*
X219464Y374617D01*
X219436Y374506D01*
X219394Y374354D01*
X219352Y374146D01*
X219325Y373896D01*
X219311Y373605D01*
X219297Y373272D01*
Y369666D01*
X218118D01*
Y376628D01*
X219172D01*
Y375630D01*
X219186Y375658D01*
X219228Y375713D01*
X219311Y375810D01*
X219408Y375921D01*
X219533Y376060D01*
X219685Y376198D01*
X219852Y376337D01*
X220046Y376462D01*
X220074Y376476D01*
X220143Y376517D01*
X220254Y376559D01*
X220406Y376628D01*
X220587Y376684D01*
X220795Y376725D01*
X221031Y376767D01*
X221280Y376781D01*
X221405D01*
X221558Y376767D01*
X221724Y376739D01*
X221932Y376698D01*
X222140Y376642D01*
X222348Y376559D01*
X222542Y376448D01*
X222570Y376434D01*
X222626Y376393D01*
X222709Y376323D01*
X222820Y376212D01*
X222931Y376087D01*
X223055Y375935D01*
X223166Y375755D01*
X223250Y375547D01*
X223263Y375560D01*
X223291Y375602D01*
X223333Y375658D01*
X223402Y375741D01*
X223485Y375838D01*
X223582Y375935D01*
X223693Y376046D01*
X223832Y376171D01*
X223985Y376282D01*
X224137Y376393D01*
X224317Y376490D01*
X224512Y376587D01*
X224720Y376670D01*
X224942Y376725D01*
X225163Y376767D01*
X225413Y376781D01*
X225510D01*
X225579Y376767D01*
D02*
G37*
G36*
X216329Y369666D02*
X215150D01*
Y376628D01*
X216329D01*
Y369666D01*
D02*
G37*
G36*
X213986Y378126D02*
X210823D01*
Y369666D01*
X209548D01*
Y378126D01*
X206386D01*
Y379263D01*
X213986D01*
Y378126D01*
D02*
G37*
G36*
X205151Y369666D02*
X203972D01*
Y376628D01*
X205151D01*
Y369666D01*
D02*
G37*
G36*
X232389Y376767D02*
X232500Y376753D01*
X232638Y376725D01*
X232791Y376698D01*
X232971Y376656D01*
X233138Y376614D01*
X233332Y376545D01*
X233512Y376476D01*
X233706Y376379D01*
X233901Y376268D01*
X234095Y376143D01*
X234275Y375990D01*
X234441Y375824D01*
X234455Y375810D01*
X234483Y375782D01*
X234525Y375727D01*
X234580Y375644D01*
X234649Y375547D01*
X234719Y375436D01*
X234802Y375297D01*
X234885Y375131D01*
X234968Y374950D01*
X235052Y374756D01*
X235121Y374534D01*
X235190Y374299D01*
X235246Y374035D01*
X235287Y373758D01*
X235315Y373466D01*
X235329Y373147D01*
Y373134D01*
Y373078D01*
Y372981D01*
X235315Y372842D01*
X230114D01*
Y372828D01*
Y372787D01*
X230128Y372731D01*
Y372648D01*
X230142Y372551D01*
X230170Y372440D01*
X230212Y372191D01*
X230295Y371913D01*
X230406Y371608D01*
X230558Y371331D01*
X230752Y371081D01*
X230766D01*
X230780Y371053D01*
X230863Y370984D01*
X230988Y370887D01*
X231155Y370790D01*
X231376Y370679D01*
X231626Y370582D01*
X231903Y370512D01*
X232056Y370499D01*
X232222Y370485D01*
X232333D01*
X232458Y370499D01*
X232611Y370526D01*
X232777Y370568D01*
X232971Y370623D01*
X233152Y370706D01*
X233332Y370817D01*
X233346Y370831D01*
X233415Y370887D01*
X233498Y370970D01*
X233595Y371081D01*
X233706Y371233D01*
X233831Y371428D01*
X233956Y371650D01*
X234067Y371913D01*
X235287Y371760D01*
Y371747D01*
X235273Y371719D01*
X235260Y371664D01*
X235232Y371580D01*
X235190Y371497D01*
X235149Y371386D01*
X235038Y371150D01*
X234899Y370887D01*
X234705Y370610D01*
X234483Y370346D01*
X234206Y370096D01*
X234192D01*
X234164Y370069D01*
X234122Y370041D01*
X234067Y369999D01*
X233984Y369958D01*
X233901Y369916D01*
X233790Y369861D01*
X233665Y369805D01*
X233526Y369750D01*
X233387Y369694D01*
X233041Y369611D01*
X232652Y369542D01*
X232222Y369514D01*
X232070D01*
X231973Y369528D01*
X231848Y369542D01*
X231695Y369569D01*
X231529Y369597D01*
X231349Y369625D01*
X230960Y369736D01*
X230752Y369819D01*
X230558Y369902D01*
X230350Y370013D01*
X230156Y370138D01*
X229976Y370277D01*
X229795Y370443D01*
X229782Y370457D01*
X229754Y370485D01*
X229712Y370540D01*
X229657Y370623D01*
X229587Y370720D01*
X229518Y370831D01*
X229435Y370970D01*
X229352Y371123D01*
X229268Y371303D01*
X229185Y371497D01*
X229116Y371719D01*
X229047Y371955D01*
X228991Y372204D01*
X228950Y372482D01*
X228922Y372773D01*
X228908Y373078D01*
Y373092D01*
Y373161D01*
Y373245D01*
X228922Y373369D01*
X228936Y373522D01*
X228950Y373688D01*
X228977Y373882D01*
X229019Y374077D01*
X229130Y374520D01*
X229199Y374742D01*
X229282Y374978D01*
X229393Y375200D01*
X229518Y375408D01*
X229657Y375616D01*
X229809Y375810D01*
X229823Y375824D01*
X229851Y375852D01*
X229906Y375893D01*
X229976Y375963D01*
X230059Y376032D01*
X230170Y376115D01*
X230295Y376212D01*
X230447Y376296D01*
X230600Y376393D01*
X230780Y376476D01*
X230974Y376559D01*
X231182Y376628D01*
X231404Y376698D01*
X231640Y376739D01*
X231890Y376767D01*
X232153Y376781D01*
X232292D01*
X232389Y376767D01*
D02*
G37*
G36*
X43119Y358964D02*
X41940D01*
Y360309D01*
X43119D01*
Y358964D01*
D02*
G37*
G36*
X24868Y360461D02*
X24993Y360448D01*
X25146Y360434D01*
X25298Y360420D01*
X25478Y360378D01*
X25853Y360295D01*
X26269Y360170D01*
X26477Y360087D01*
X26671Y359990D01*
X26865Y359865D01*
X27059Y359740D01*
X27073Y359726D01*
X27101Y359712D01*
X27157Y359671D01*
X27226Y359602D01*
X27295Y359532D01*
X27392Y359435D01*
X27489Y359324D01*
X27600Y359213D01*
X27711Y359075D01*
X27822Y358908D01*
X27947Y358742D01*
X28058Y358561D01*
X28155Y358353D01*
X28266Y358145D01*
X28349Y357923D01*
X28432Y357674D01*
X27184Y357383D01*
Y357396D01*
X27170Y357424D01*
X27143Y357480D01*
X27115Y357549D01*
X27087Y357632D01*
X27046Y357743D01*
X26935Y357965D01*
X26796Y358215D01*
X26630Y358464D01*
X26421Y358700D01*
X26200Y358908D01*
X26172Y358936D01*
X26089Y358991D01*
X25950Y359061D01*
X25770Y359158D01*
X25534Y359241D01*
X25270Y359324D01*
X24951Y359380D01*
X24605Y359394D01*
X24494D01*
X24424Y359380D01*
X24327D01*
X24216Y359366D01*
X23953Y359324D01*
X23662Y359269D01*
X23356Y359172D01*
X23038Y359033D01*
X22746Y358853D01*
X22733D01*
X22719Y358825D01*
X22622Y358755D01*
X22497Y358645D01*
X22344Y358478D01*
X22164Y358270D01*
X21997Y358034D01*
X21845Y357743D01*
X21706Y357424D01*
Y357410D01*
X21692Y357383D01*
X21679Y357341D01*
X21665Y357272D01*
X21637Y357188D01*
X21609Y357091D01*
X21567Y356856D01*
X21512Y356578D01*
X21457Y356273D01*
X21429Y355940D01*
X21415Y355580D01*
Y355566D01*
Y355524D01*
Y355455D01*
Y355372D01*
X21429Y355275D01*
Y355150D01*
X21443Y355011D01*
X21457Y354859D01*
X21498Y354526D01*
X21567Y354165D01*
X21651Y353805D01*
X21762Y353444D01*
Y353430D01*
X21776Y353402D01*
X21803Y353361D01*
X21831Y353291D01*
X21914Y353125D01*
X22039Y352931D01*
X22192Y352709D01*
X22386Y352473D01*
X22608Y352265D01*
X22871Y352071D01*
X22885D01*
X22913Y352057D01*
X22954Y352029D01*
X23010Y352002D01*
X23079Y351974D01*
X23162Y351932D01*
X23356Y351849D01*
X23606Y351766D01*
X23884Y351697D01*
X24189Y351641D01*
X24508Y351627D01*
X24605D01*
X24688Y351641D01*
X24785D01*
X24882Y351655D01*
X25132Y351710D01*
X25423Y351780D01*
X25714Y351891D01*
X26019Y352043D01*
X26172Y352126D01*
X26311Y352237D01*
X26324Y352251D01*
X26338Y352265D01*
X26380Y352307D01*
X26435Y352348D01*
X26491Y352418D01*
X26560Y352501D01*
X26643Y352584D01*
X26713Y352695D01*
X26796Y352820D01*
X26893Y352959D01*
X26976Y353097D01*
X27059Y353264D01*
X27129Y353444D01*
X27198Y353638D01*
X27267Y353846D01*
X27323Y354068D01*
X28599Y353749D01*
Y353735D01*
X28585Y353680D01*
X28557Y353596D01*
X28516Y353486D01*
X28474Y353361D01*
X28419Y353208D01*
X28349Y353042D01*
X28266Y352862D01*
X28072Y352473D01*
X27822Y352085D01*
X27670Y351891D01*
X27517Y351697D01*
X27351Y351530D01*
X27157Y351364D01*
X27143Y351350D01*
X27115Y351322D01*
X27046Y351294D01*
X26976Y351239D01*
X26865Y351170D01*
X26754Y351100D01*
X26602Y351031D01*
X26449Y350961D01*
X26269Y350878D01*
X26075Y350809D01*
X25867Y350740D01*
X25645Y350670D01*
X25409Y350615D01*
X25159Y350587D01*
X24896Y350559D01*
X24619Y350546D01*
X24466D01*
X24355Y350559D01*
X24230D01*
X24078Y350573D01*
X23911Y350601D01*
X23717Y350629D01*
X23315Y350698D01*
X22899Y350809D01*
X22483Y350961D01*
X22289Y351059D01*
X22095Y351170D01*
X22081Y351183D01*
X22053Y351197D01*
X21997Y351239D01*
X21942Y351294D01*
X21859Y351350D01*
X21762Y351433D01*
X21651Y351530D01*
X21540Y351641D01*
X21429Y351766D01*
X21304Y351891D01*
X21054Y352210D01*
X20819Y352584D01*
X20611Y353000D01*
Y353014D01*
X20583Y353056D01*
X20569Y353125D01*
X20527Y353208D01*
X20500Y353319D01*
X20458Y353458D01*
X20403Y353610D01*
X20361Y353777D01*
X20319Y353957D01*
X20264Y354165D01*
X20194Y354595D01*
X20139Y355080D01*
X20111Y355580D01*
Y355593D01*
Y355649D01*
Y355732D01*
X20125Y355829D01*
Y355968D01*
X20139Y356107D01*
X20153Y356287D01*
X20181Y356467D01*
X20250Y356869D01*
X20347Y357313D01*
X20486Y357757D01*
X20680Y358187D01*
X20694Y358201D01*
X20708Y358242D01*
X20735Y358298D01*
X20791Y358367D01*
X20846Y358464D01*
X20916Y358575D01*
X21096Y358825D01*
X21332Y359102D01*
X21609Y359380D01*
X21928Y359657D01*
X22302Y359893D01*
X22316Y359907D01*
X22358Y359921D01*
X22413Y359948D01*
X22483Y359990D01*
X22594Y360031D01*
X22705Y360073D01*
X22843Y360129D01*
X22996Y360184D01*
X23162Y360239D01*
X23343Y360295D01*
X23731Y360378D01*
X24175Y360448D01*
X24632Y360475D01*
X24771D01*
X24868Y360461D01*
D02*
G37*
G36*
X40248Y357812D02*
X40401Y357785D01*
X40581Y357729D01*
X40775Y357660D01*
X40997Y357563D01*
X41233Y357438D01*
X40803Y356356D01*
X40789Y356370D01*
X40734Y356398D01*
X40650Y356440D01*
X40539Y356481D01*
X40415Y356523D01*
X40262Y356564D01*
X40110Y356592D01*
X39957Y356606D01*
X39888D01*
X39818Y356592D01*
X39721Y356578D01*
X39624Y356550D01*
X39499Y356509D01*
X39374Y356453D01*
X39264Y356370D01*
X39250Y356356D01*
X39208Y356329D01*
X39167Y356273D01*
X39097Y356204D01*
X39028Y356107D01*
X38958Y355996D01*
X38889Y355871D01*
X38834Y355718D01*
X38820Y355691D01*
X38806Y355607D01*
X38778Y355483D01*
X38737Y355316D01*
X38695Y355108D01*
X38667Y354872D01*
X38653Y354623D01*
X38640Y354345D01*
Y350712D01*
X37461D01*
Y357674D01*
X38529D01*
Y356620D01*
X38542Y356634D01*
X38598Y356731D01*
X38667Y356856D01*
X38778Y357008D01*
X38889Y357161D01*
X39014Y357327D01*
X39139Y357466D01*
X39264Y357577D01*
X39278Y357591D01*
X39319Y357618D01*
X39402Y357660D01*
X39485Y357701D01*
X39596Y357743D01*
X39735Y357785D01*
X39874Y357812D01*
X40026Y357826D01*
X40123D01*
X40248Y357812D01*
D02*
G37*
G36*
X92976Y357812D02*
X93184Y357799D01*
X93406Y357771D01*
X93642Y357715D01*
X93891Y357660D01*
X94127Y357577D01*
X94141D01*
X94155Y357563D01*
X94224Y357535D01*
X94335Y357480D01*
X94474Y357410D01*
X94626Y357313D01*
X94779Y357202D01*
X94917Y357077D01*
X95042Y356939D01*
X95056Y356925D01*
X95084Y356870D01*
X95139Y356772D01*
X95209Y356661D01*
X95278Y356495D01*
X95347Y356315D01*
X95403Y356107D01*
X95458Y355871D01*
X94307Y355718D01*
Y355746D01*
X94293Y355802D01*
X94266Y355899D01*
X94224Y356023D01*
X94155Y356148D01*
X94072Y356287D01*
X93974Y356426D01*
X93836Y356550D01*
X93822Y356564D01*
X93766Y356592D01*
X93683Y356648D01*
X93558Y356703D01*
X93420Y356758D01*
X93239Y356814D01*
X93018Y356842D01*
X92782Y356856D01*
X92643Y356856D01*
X92504Y356842D01*
X92324Y356828D01*
X92144Y356786D01*
X91950Y356745D01*
X91769Y356675D01*
X91617Y356578D01*
X91603Y356564D01*
X91561Y356537D01*
X91506Y356481D01*
X91450Y356398D01*
X91381Y356315D01*
X91326Y356204D01*
X91284Y356079D01*
X91270Y355954D01*
Y355940D01*
Y355913D01*
X91284Y355871D01*
Y355815D01*
X91326Y355677D01*
X91409Y355538D01*
X91423Y355524D01*
X91437Y355510D01*
X91464Y355469D01*
X91520Y355427D01*
X91575Y355386D01*
X91658Y355330D01*
X91756Y355288D01*
X91866Y355233D01*
X91880D01*
X91908Y355219D01*
X91964Y355205D01*
X92061Y355164D01*
X92199Y355122D01*
X92380Y355080D01*
X92491Y355039D01*
X92615Y355011D01*
X92754Y354969D01*
X92907Y354928D01*
X92920D01*
X92962Y354914D01*
X93031Y354900D01*
X93115Y354872D01*
X93212Y354845D01*
X93336Y354817D01*
X93600Y354734D01*
X93891Y354650D01*
X94183Y354553D01*
X94446Y354456D01*
X94557Y354415D01*
X94654Y354373D01*
X94682Y354359D01*
X94737Y354332D01*
X94820Y354290D01*
X94945Y354221D01*
X95070Y354137D01*
X95195Y354026D01*
X95320Y353902D01*
X95431Y353763D01*
X95444Y353749D01*
X95472Y353694D01*
X95528Y353610D01*
X95583Y353486D01*
X95625Y353333D01*
X95680Y353167D01*
X95708Y352972D01*
X95722Y352751D01*
Y352723D01*
Y352654D01*
X95708Y352542D01*
X95680Y352390D01*
X95639Y352224D01*
X95569Y352043D01*
X95486Y351835D01*
X95375Y351641D01*
X95361Y351613D01*
X95306Y351558D01*
X95237Y351461D01*
X95126Y351350D01*
X94973Y351225D01*
X94806Y351086D01*
X94612Y350961D01*
X94377Y350837D01*
X94363D01*
X94349Y350823D01*
X94266Y350795D01*
X94127Y350754D01*
X93947Y350698D01*
X93725Y350643D01*
X93475Y350601D01*
X93212Y350573D01*
X92907Y350559D01*
X92782D01*
X92685Y350573D01*
X92574D01*
X92435Y350587D01*
X92296Y350601D01*
X92144Y350629D01*
X91811Y350698D01*
X91464Y350795D01*
X91131Y350934D01*
X90979Y351017D01*
X90840Y351114D01*
X90826Y351128D01*
X90812Y351142D01*
X90729Y351225D01*
X90604Y351350D01*
X90466Y351544D01*
X90313Y351780D01*
X90161Y352057D01*
X90036Y352404D01*
X89939Y352792D01*
X91104Y352972D01*
Y352959D01*
Y352945D01*
X91131Y352862D01*
X91159Y352723D01*
X91215Y352570D01*
X91284Y352404D01*
X91367Y352224D01*
X91492Y352043D01*
X91644Y351891D01*
X91672Y351877D01*
X91728Y351835D01*
X91839Y351780D01*
X91977Y351710D01*
X92158Y351641D01*
X92366Y351586D01*
X92615Y351544D01*
X92907Y351530D01*
X93045D01*
X93184Y351544D01*
X93364Y351572D01*
X93558Y351613D01*
X93766Y351669D01*
X93947Y351738D01*
X94113Y351849D01*
X94127Y351863D01*
X94183Y351905D01*
X94238Y351974D01*
X94321Y352071D01*
X94390Y352182D01*
X94460Y352321D01*
X94501Y352459D01*
X94515Y352626D01*
Y352640D01*
Y352695D01*
X94501Y352764D01*
X94474Y352862D01*
X94432Y352959D01*
X94363Y353056D01*
X94279Y353167D01*
X94155Y353250D01*
X94141Y353264D01*
X94099Y353278D01*
X94030Y353319D01*
X93919Y353361D01*
X93752Y353416D01*
X93656Y353458D01*
X93545Y353486D01*
X93420Y353527D01*
X93281Y353569D01*
X93128Y353610D01*
X92948Y353652D01*
X92934D01*
X92893Y353666D01*
X92823Y353680D01*
X92740Y353707D01*
X92629Y353735D01*
X92504Y353777D01*
X92241Y353846D01*
X91936Y353943D01*
X91644Y354026D01*
X91367Y354123D01*
X91242Y354179D01*
X91145Y354221D01*
X91117Y354234D01*
X91062Y354262D01*
X90979Y354318D01*
X90868Y354387D01*
X90743Y354484D01*
X90618Y354595D01*
X90493Y354720D01*
X90382Y354872D01*
X90369Y354886D01*
X90341Y354942D01*
X90299Y355039D01*
X90258Y355150D01*
X90216Y355288D01*
X90175Y355455D01*
X90147Y355621D01*
X90133Y355815D01*
Y355843D01*
Y355899D01*
X90147Y355982D01*
X90161Y356107D01*
X90188Y356231D01*
X90216Y356384D01*
X90272Y356523D01*
X90341Y356675D01*
X90355Y356689D01*
X90382Y356745D01*
X90424Y356814D01*
X90493Y356911D01*
X90577Y357008D01*
X90674Y357133D01*
X90785Y357244D01*
X90923Y357341D01*
X90937Y357355D01*
X90979Y357369D01*
X91034Y357410D01*
X91117Y357452D01*
X91229Y357507D01*
X91353Y357563D01*
X91506Y357618D01*
X91672Y357674D01*
X91700Y357688D01*
X91756Y357701D01*
X91853Y357729D01*
X91977Y357757D01*
X92130Y357785D01*
X92296Y357799D01*
X92491Y357826D01*
X92823Y357826D01*
X92976Y357812D01*
D02*
G37*
G36*
X47488Y357812D02*
X47696Y357799D01*
X47917Y357771D01*
X48153Y357715D01*
X48403Y357660D01*
X48639Y357577D01*
X48653D01*
X48666Y357563D01*
X48736Y357535D01*
X48847Y357480D01*
X48985Y357410D01*
X49138Y357313D01*
X49290Y357202D01*
X49429Y357077D01*
X49554Y356939D01*
X49568Y356925D01*
X49596Y356869D01*
X49651Y356772D01*
X49720Y356661D01*
X49790Y356495D01*
X49859Y356315D01*
X49914Y356107D01*
X49970Y355871D01*
X48819Y355718D01*
Y355746D01*
X48805Y355802D01*
X48777Y355899D01*
X48736Y356023D01*
X48666Y356148D01*
X48583Y356287D01*
X48486Y356426D01*
X48347Y356550D01*
X48334Y356564D01*
X48278Y356592D01*
X48195Y356647D01*
X48070Y356703D01*
X47931Y356758D01*
X47751Y356814D01*
X47529Y356842D01*
X47293Y356856D01*
X47155D01*
X47016Y356842D01*
X46836Y356828D01*
X46656Y356786D01*
X46461Y356745D01*
X46281Y356675D01*
X46129Y356578D01*
X46115Y356564D01*
X46073Y356537D01*
X46017Y356481D01*
X45962Y356398D01*
X45893Y356315D01*
X45837Y356204D01*
X45796Y356079D01*
X45782Y355954D01*
Y355940D01*
Y355913D01*
X45796Y355871D01*
Y355815D01*
X45837Y355677D01*
X45920Y355538D01*
X45934Y355524D01*
X45948Y355510D01*
X45976Y355469D01*
X46031Y355427D01*
X46087Y355386D01*
X46170Y355330D01*
X46267Y355288D01*
X46378Y355233D01*
X46392D01*
X46420Y355219D01*
X46475Y355205D01*
X46572Y355164D01*
X46711Y355122D01*
X46891Y355080D01*
X47002Y355039D01*
X47127Y355011D01*
X47266Y354969D01*
X47418Y354928D01*
X47432D01*
X47474Y354914D01*
X47543Y354900D01*
X47626Y354872D01*
X47723Y354845D01*
X47848Y354817D01*
X48112Y354734D01*
X48403Y354650D01*
X48694Y354553D01*
X48958Y354456D01*
X49069Y354415D01*
X49166Y354373D01*
X49193Y354359D01*
X49249Y354332D01*
X49332Y354290D01*
X49457Y354221D01*
X49582Y354137D01*
X49707Y354026D01*
X49831Y353902D01*
X49942Y353763D01*
X49956Y353749D01*
X49984Y353694D01*
X50039Y353610D01*
X50095Y353486D01*
X50136Y353333D01*
X50192Y353167D01*
X50220Y352972D01*
X50233Y352751D01*
Y352723D01*
Y352653D01*
X50220Y352542D01*
X50192Y352390D01*
X50150Y352224D01*
X50081Y352043D01*
X49998Y351835D01*
X49887Y351641D01*
X49873Y351613D01*
X49818Y351558D01*
X49748Y351461D01*
X49637Y351350D01*
X49485Y351225D01*
X49318Y351086D01*
X49124Y350961D01*
X48888Y350837D01*
X48874D01*
X48861Y350823D01*
X48777Y350795D01*
X48639Y350754D01*
X48458Y350698D01*
X48236Y350643D01*
X47987Y350601D01*
X47723Y350573D01*
X47418Y350559D01*
X47293D01*
X47196Y350573D01*
X47085D01*
X46947Y350587D01*
X46808Y350601D01*
X46656Y350629D01*
X46323Y350698D01*
X45976Y350795D01*
X45643Y350934D01*
X45490Y351017D01*
X45352Y351114D01*
X45338Y351128D01*
X45324Y351142D01*
X45241Y351225D01*
X45116Y351350D01*
X44977Y351544D01*
X44825Y351780D01*
X44672Y352057D01*
X44548Y352404D01*
X44450Y352792D01*
X45615Y352972D01*
Y352959D01*
Y352945D01*
X45643Y352862D01*
X45671Y352723D01*
X45726Y352570D01*
X45796Y352404D01*
X45879Y352224D01*
X46004Y352043D01*
X46156Y351891D01*
X46184Y351877D01*
X46239Y351835D01*
X46350Y351780D01*
X46489Y351710D01*
X46669Y351641D01*
X46877Y351586D01*
X47127Y351544D01*
X47418Y351530D01*
X47557D01*
X47696Y351544D01*
X47876Y351572D01*
X48070Y351613D01*
X48278Y351669D01*
X48458Y351738D01*
X48625Y351849D01*
X48639Y351863D01*
X48694Y351905D01*
X48750Y351974D01*
X48833Y352071D01*
X48902Y352182D01*
X48972Y352321D01*
X49013Y352459D01*
X49027Y352626D01*
Y352640D01*
Y352695D01*
X49013Y352764D01*
X48985Y352862D01*
X48944Y352959D01*
X48874Y353056D01*
X48791Y353167D01*
X48666Y353250D01*
X48653Y353264D01*
X48611Y353278D01*
X48542Y353319D01*
X48431Y353361D01*
X48264Y353416D01*
X48167Y353458D01*
X48056Y353486D01*
X47931Y353527D01*
X47793Y353569D01*
X47640Y353610D01*
X47460Y353652D01*
X47446D01*
X47404Y353666D01*
X47335Y353680D01*
X47252Y353707D01*
X47141Y353735D01*
X47016Y353777D01*
X46753Y353846D01*
X46447Y353943D01*
X46156Y354026D01*
X45879Y354123D01*
X45754Y354179D01*
X45657Y354221D01*
X45629Y354234D01*
X45574Y354262D01*
X45490Y354318D01*
X45380Y354387D01*
X45255Y354484D01*
X45130Y354595D01*
X45005Y354720D01*
X44894Y354872D01*
X44880Y354886D01*
X44853Y354942D01*
X44811Y355039D01*
X44769Y355150D01*
X44728Y355288D01*
X44686Y355455D01*
X44658Y355621D01*
X44644Y355815D01*
Y355843D01*
Y355899D01*
X44658Y355982D01*
X44672Y356107D01*
X44700Y356231D01*
X44728Y356384D01*
X44783Y356523D01*
X44853Y356675D01*
X44866Y356689D01*
X44894Y356745D01*
X44936Y356814D01*
X45005Y356911D01*
X45088Y357008D01*
X45185Y357133D01*
X45296Y357244D01*
X45435Y357341D01*
X45449Y357355D01*
X45490Y357369D01*
X45546Y357410D01*
X45629Y357452D01*
X45740Y357507D01*
X45865Y357563D01*
X46017Y357618D01*
X46184Y357674D01*
X46212Y357688D01*
X46267Y357701D01*
X46364Y357729D01*
X46489Y357757D01*
X46642Y357785D01*
X46808Y357799D01*
X47002Y357826D01*
X47335D01*
X47488Y357812D01*
D02*
G37*
G36*
X81118Y350712D02*
X79940D01*
Y360309D01*
X81118D01*
Y350712D01*
D02*
G37*
G36*
X60094Y360295D02*
X60219D01*
X60510Y360281D01*
X60815Y360239D01*
X61148Y360198D01*
X61453Y360129D01*
X61606Y360087D01*
X61730Y360045D01*
X61744D01*
X61758Y360031D01*
X61841Y359990D01*
X61966Y359934D01*
X62119Y359837D01*
X62285Y359712D01*
X62465Y359546D01*
X62632Y359352D01*
X62798Y359130D01*
Y359116D01*
X62812Y359102D01*
X62868Y359019D01*
X62923Y358880D01*
X63006Y358700D01*
X63076Y358492D01*
X63145Y358242D01*
X63187Y357979D01*
X63200Y357688D01*
Y357674D01*
Y357646D01*
Y357591D01*
X63187Y357521D01*
Y357424D01*
X63173Y357327D01*
X63117Y357091D01*
X63034Y356814D01*
X62923Y356523D01*
X62757Y356231D01*
X62646Y356093D01*
X62535Y355954D01*
X62521Y355940D01*
X62507Y355926D01*
X62465Y355885D01*
X62410Y355843D01*
X62341Y355788D01*
X62257Y355732D01*
X62147Y355663D01*
X62035Y355580D01*
X61897Y355510D01*
X61744Y355441D01*
X61578Y355358D01*
X61398Y355288D01*
X61189Y355233D01*
X60981Y355164D01*
X60746Y355122D01*
X60496Y355080D01*
X60524Y355066D01*
X60579Y355039D01*
X60662Y354983D01*
X60774Y354928D01*
X61023Y354775D01*
X61148Y354678D01*
X61259Y354595D01*
X61287Y354567D01*
X61356Y354498D01*
X61467Y354387D01*
X61606Y354248D01*
X61758Y354054D01*
X61938Y353846D01*
X62119Y353596D01*
X62313Y353319D01*
X63963Y350712D01*
X62382D01*
X61120Y352709D01*
Y352723D01*
X61093Y352751D01*
X61065Y352792D01*
X61023Y352848D01*
X60926Y353000D01*
X60801Y353194D01*
X60649Y353402D01*
X60496Y353624D01*
X60344Y353832D01*
X60205Y354026D01*
X60191Y354040D01*
X60149Y354096D01*
X60080Y354179D01*
X59983Y354276D01*
X59775Y354484D01*
X59664Y354581D01*
X59553Y354664D01*
X59539Y354678D01*
X59511Y354692D01*
X59456Y354720D01*
X59373Y354761D01*
X59290Y354803D01*
X59193Y354845D01*
X58971Y354914D01*
X58957D01*
X58929Y354928D01*
X58874D01*
X58804Y354942D01*
X58707Y354956D01*
X58596D01*
X58444Y354969D01*
X56807D01*
Y350712D01*
X55531D01*
Y360309D01*
X59983D01*
X60094Y360295D01*
D02*
G37*
G36*
X43119Y350712D02*
X41940D01*
Y357674D01*
X43119D01*
Y350712D01*
D02*
G37*
G36*
X31192Y356869D02*
X31206Y356883D01*
X31234Y356911D01*
X31275Y356953D01*
X31345Y357022D01*
X31414Y357091D01*
X31511Y357174D01*
X31636Y357258D01*
X31761Y357355D01*
X31899Y357438D01*
X32052Y357521D01*
X32413Y357674D01*
X32607Y357743D01*
X32815Y357785D01*
X33037Y357812D01*
X33259Y357826D01*
X33383D01*
X33536Y357812D01*
X33716Y357785D01*
X33924Y357757D01*
X34146Y357701D01*
X34368Y357618D01*
X34590Y357521D01*
X34618Y357507D01*
X34687Y357466D01*
X34784Y357396D01*
X34909Y357299D01*
X35034Y357174D01*
X35172Y357036D01*
X35297Y356869D01*
X35408Y356675D01*
X35422Y356647D01*
X35450Y356578D01*
X35491Y356453D01*
X35533Y356273D01*
X35575Y356051D01*
X35616Y355788D01*
X35644Y355469D01*
X35658Y355108D01*
Y350712D01*
X34479D01*
Y355122D01*
Y355136D01*
Y355164D01*
Y355205D01*
Y355261D01*
X34465Y355413D01*
X34437Y355607D01*
X34382Y355815D01*
X34313Y356023D01*
X34216Y356231D01*
X34091Y356398D01*
X34077Y356412D01*
X34021Y356467D01*
X33938Y356537D01*
X33813Y356606D01*
X33661Y356689D01*
X33481Y356745D01*
X33259Y356800D01*
X33009Y356814D01*
X32926D01*
X32829Y356800D01*
X32690Y356786D01*
X32551Y356745D01*
X32385Y356703D01*
X32218Y356634D01*
X32038Y356537D01*
X32024Y356523D01*
X31969Y356481D01*
X31886Y356426D01*
X31788Y356342D01*
X31678Y356231D01*
X31567Y356107D01*
X31470Y355954D01*
X31386Y355788D01*
X31372Y355760D01*
X31359Y355704D01*
X31331Y355593D01*
X31289Y355455D01*
X31248Y355275D01*
X31220Y355053D01*
X31206Y354803D01*
X31192Y354512D01*
Y350712D01*
X30013D01*
Y360309D01*
X31192D01*
Y356869D01*
D02*
G37*
G36*
X86028Y357812D02*
X86139Y357799D01*
X86278Y357771D01*
X86430Y357743D01*
X86610Y357701D01*
X86777Y357660D01*
X86971Y357591D01*
X87151Y357521D01*
X87345Y357424D01*
X87540Y357313D01*
X87734Y357188D01*
X87914Y357036D01*
X88080Y356869D01*
X88094Y356856D01*
X88122Y356828D01*
X88164Y356772D01*
X88219Y356689D01*
X88288Y356592D01*
X88358Y356481D01*
X88441Y356342D01*
X88524Y356176D01*
X88607Y355996D01*
X88691Y355802D01*
X88760Y355580D01*
X88829Y355344D01*
X88885Y355080D01*
X88926Y354803D01*
X88954Y354512D01*
X88968Y354193D01*
Y354179D01*
Y354123D01*
Y354026D01*
X88954Y353888D01*
X83753D01*
Y353874D01*
Y353832D01*
X83767Y353777D01*
Y353694D01*
X83781Y353596D01*
X83809Y353486D01*
X83850Y353236D01*
X83934Y352959D01*
X84045Y352653D01*
X84197Y352376D01*
X84391Y352126D01*
X84405D01*
X84419Y352099D01*
X84502Y352029D01*
X84627Y351932D01*
X84794Y351835D01*
X85015Y351724D01*
X85265Y351627D01*
X85542Y351558D01*
X85695Y351544D01*
X85861Y351530D01*
X85972D01*
X86097Y351544D01*
X86250Y351572D01*
X86416Y351613D01*
X86610Y351669D01*
X86791Y351752D01*
X86971Y351863D01*
X86985Y351877D01*
X87054Y351932D01*
X87137Y352015D01*
X87234Y352126D01*
X87345Y352279D01*
X87470Y352473D01*
X87595Y352695D01*
X87706Y352959D01*
X88926Y352806D01*
Y352792D01*
X88912Y352764D01*
X88899Y352709D01*
X88871Y352626D01*
X88829Y352542D01*
X88788Y352432D01*
X88677Y352196D01*
X88538Y351932D01*
X88344Y351655D01*
X88122Y351391D01*
X87845Y351142D01*
X87831D01*
X87803Y351114D01*
X87761Y351086D01*
X87706Y351045D01*
X87623Y351003D01*
X87540Y350961D01*
X87429Y350906D01*
X87304Y350851D01*
X87165Y350795D01*
X87026Y350740D01*
X86680Y350656D01*
X86291Y350587D01*
X85861Y350559D01*
X85709D01*
X85612Y350573D01*
X85487Y350587D01*
X85334Y350615D01*
X85168Y350643D01*
X84988Y350670D01*
X84599Y350781D01*
X84391Y350864D01*
X84197Y350948D01*
X83989Y351059D01*
X83795Y351183D01*
X83615Y351322D01*
X83434Y351488D01*
X83421Y351502D01*
X83393Y351530D01*
X83351Y351586D01*
X83296Y351669D01*
X83226Y351766D01*
X83157Y351877D01*
X83074Y352015D01*
X82991Y352168D01*
X82907Y352348D01*
X82824Y352542D01*
X82755Y352764D01*
X82686Y353000D01*
X82630Y353250D01*
X82589Y353527D01*
X82561Y353818D01*
X82547Y354123D01*
Y354137D01*
Y354207D01*
Y354290D01*
X82561Y354415D01*
X82575Y354567D01*
X82589Y354734D01*
X82616Y354928D01*
X82658Y355122D01*
X82769Y355566D01*
X82838Y355788D01*
X82921Y356023D01*
X83032Y356245D01*
X83157Y356453D01*
X83296Y356661D01*
X83448Y356856D01*
X83462Y356869D01*
X83490Y356897D01*
X83545Y356939D01*
X83615Y357008D01*
X83698Y357077D01*
X83809Y357161D01*
X83934Y357258D01*
X84086Y357341D01*
X84239Y357438D01*
X84419Y357521D01*
X84613Y357604D01*
X84821Y357674D01*
X85043Y357743D01*
X85279Y357785D01*
X85529Y357812D01*
X85792Y357826D01*
X85931D01*
X86028Y357812D01*
D02*
G37*
G36*
X73657Y356883D02*
X73671Y356897D01*
X73685Y356925D01*
X73727Y356967D01*
X73796Y357036D01*
X73865Y357105D01*
X73948Y357188D01*
X74059Y357272D01*
X74170Y357355D01*
X74448Y357535D01*
X74767Y357674D01*
X74947Y357743D01*
X75141Y357785D01*
X75349Y357812D01*
X75557Y357826D01*
X75668D01*
X75793Y357812D01*
X75946Y357799D01*
X76126Y357757D01*
X76334Y357715D01*
X76556Y357646D01*
X76764Y357563D01*
X76792Y357549D01*
X76861Y357521D01*
X76972Y357452D01*
X77097Y357369D01*
X77249Y357272D01*
X77402Y357147D01*
X77568Y356994D01*
X77707Y356828D01*
X77721Y356814D01*
X77762Y356745D01*
X77832Y356647D01*
X77915Y356523D01*
X78012Y356356D01*
X78109Y356162D01*
X78206Y355940D01*
X78289Y355704D01*
Y355691D01*
X78303Y355677D01*
X78317Y355635D01*
X78331Y355593D01*
X78359Y355455D01*
X78400Y355275D01*
X78442Y355066D01*
X78483Y354831D01*
X78497Y354567D01*
X78511Y354290D01*
Y354276D01*
Y354207D01*
Y354123D01*
X78497Y353999D01*
X78483Y353846D01*
X78470Y353680D01*
X78442Y353486D01*
X78400Y353278D01*
X78289Y352834D01*
X78220Y352598D01*
X78137Y352376D01*
X78040Y352140D01*
X77915Y351932D01*
X77776Y351724D01*
X77624Y351530D01*
X77610Y351516D01*
X77582Y351488D01*
X77540Y351447D01*
X77471Y351378D01*
X77374Y351308D01*
X77277Y351225D01*
X77166Y351142D01*
X77027Y351045D01*
X76875Y350961D01*
X76722Y350864D01*
X76348Y350712D01*
X76153Y350643D01*
X75946Y350601D01*
X75724Y350573D01*
X75502Y350559D01*
X75446D01*
X75377Y350573D01*
X75294D01*
X75197Y350587D01*
X75072Y350615D01*
X74794Y350684D01*
X74642Y350740D01*
X74489Y350809D01*
X74323Y350892D01*
X74170Y350989D01*
X74004Y351114D01*
X73851Y351253D01*
X73713Y351405D01*
X73574Y351586D01*
Y350712D01*
X72478D01*
Y360309D01*
X73657D01*
Y356883D01*
D02*
G37*
G36*
X68096Y357812D02*
X68221Y357799D01*
X68359Y357771D01*
X68512Y357743D01*
X68692Y357715D01*
X69067Y357591D01*
X69261Y357521D01*
X69455Y357424D01*
X69649Y357327D01*
X69843Y357188D01*
X70024Y357050D01*
X70204Y356883D01*
X70218Y356869D01*
X70246Y356842D01*
X70287Y356786D01*
X70343Y356717D01*
X70412Y356620D01*
X70495Y356495D01*
X70578Y356356D01*
X70662Y356204D01*
X70745Y356037D01*
X70828Y355829D01*
X70911Y355621D01*
X70981Y355386D01*
X71036Y355136D01*
X71078Y354872D01*
X71105Y354595D01*
X71119Y354290D01*
Y354276D01*
Y354234D01*
Y354165D01*
Y354068D01*
X71105Y353957D01*
X71092Y353818D01*
Y353680D01*
X71064Y353527D01*
X71022Y353180D01*
X70939Y352834D01*
X70842Y352487D01*
X70703Y352168D01*
Y352154D01*
X70689Y352140D01*
X70662Y352099D01*
X70634Y352043D01*
X70537Y351905D01*
X70412Y351738D01*
X70246Y351544D01*
X70038Y351350D01*
X69802Y351156D01*
X69524Y350975D01*
X69511D01*
X69497Y350961D01*
X69455Y350934D01*
X69386Y350906D01*
X69316Y350878D01*
X69233Y350851D01*
X69025Y350767D01*
X68789Y350698D01*
X68498Y350629D01*
X68193Y350573D01*
X67860Y350559D01*
X67722D01*
X67611Y350573D01*
X67486Y350587D01*
X67347Y350615D01*
X67181Y350643D01*
X67014Y350670D01*
X66640Y350781D01*
X66432Y350864D01*
X66238Y350948D01*
X66044Y351059D01*
X65849Y351183D01*
X65669Y351322D01*
X65489Y351488D01*
X65475Y351502D01*
X65447Y351530D01*
X65406Y351586D01*
X65350Y351669D01*
X65281Y351766D01*
X65211Y351877D01*
X65128Y352015D01*
X65045Y352182D01*
X64962Y352362D01*
X64879Y352570D01*
X64809Y352792D01*
X64740Y353028D01*
X64684Y353291D01*
X64643Y353569D01*
X64615Y353874D01*
X64601Y354193D01*
Y354221D01*
Y354276D01*
X64615Y354373D01*
Y354512D01*
X64629Y354664D01*
X64657Y354859D01*
X64684Y355053D01*
X64740Y355275D01*
X64795Y355496D01*
X64865Y355732D01*
X64948Y355982D01*
X65059Y356218D01*
X65170Y356440D01*
X65322Y356661D01*
X65475Y356869D01*
X65669Y357050D01*
X65683Y357064D01*
X65711Y357077D01*
X65766Y357119D01*
X65835Y357174D01*
X65919Y357230D01*
X66030Y357299D01*
X66141Y357369D01*
X66279Y357438D01*
X66432Y357507D01*
X66598Y357577D01*
X66973Y357701D01*
X67403Y357799D01*
X67625Y357812D01*
X67860Y357826D01*
X67999D01*
X68096Y357812D01*
D02*
G37*
G36*
X28661Y391904D02*
X27483D01*
Y393250D01*
X28661D01*
Y391904D01*
D02*
G37*
G36*
X70738Y390753D02*
X70835D01*
X70932Y390739D01*
X71168Y390698D01*
X71418Y390628D01*
X71681Y390517D01*
X71945Y390379D01*
X72167Y390185D01*
X72194Y390157D01*
X72250Y390074D01*
X72347Y389949D01*
X72388Y389852D01*
X72444Y389755D01*
X72499Y389630D01*
X72541Y389505D01*
X72597Y389366D01*
X72638Y389200D01*
X72666Y389034D01*
X72694Y388839D01*
X72721Y388645D01*
Y388423D01*
Y383652D01*
X71543D01*
Y388021D01*
Y388035D01*
Y388049D01*
Y388132D01*
Y388257D01*
X71529Y388409D01*
X71515Y388576D01*
X71501Y388742D01*
X71473Y388909D01*
X71431Y389034D01*
Y389047D01*
X71404Y389089D01*
X71376Y389144D01*
X71334Y389214D01*
X71279Y389297D01*
X71210Y389380D01*
X71126Y389463D01*
X71016Y389547D01*
X71002Y389561D01*
X70960Y389574D01*
X70904Y389602D01*
X70807Y389644D01*
X70710Y389685D01*
X70585Y389713D01*
X70461Y389727D01*
X70308Y389741D01*
X70239D01*
X70183Y389727D01*
X70045Y389713D01*
X69878Y389685D01*
X69684Y389616D01*
X69476Y389533D01*
X69268Y389408D01*
X69074Y389241D01*
X69060Y389214D01*
X69005Y389144D01*
X68921Y389034D01*
X68838Y388867D01*
X68741Y388645D01*
X68672Y388382D01*
X68616Y388063D01*
X68589Y387688D01*
Y383652D01*
X67410D01*
Y388160D01*
Y388174D01*
Y388201D01*
Y388229D01*
Y388285D01*
X67396Y388437D01*
X67368Y388604D01*
X67340Y388798D01*
X67285Y388992D01*
X67215Y389172D01*
X67118Y389339D01*
X67105Y389352D01*
X67063Y389408D01*
X66994Y389463D01*
X66897Y389547D01*
X66772Y389616D01*
X66605Y389685D01*
X66411Y389727D01*
X66175Y389741D01*
X66092D01*
X65995Y389727D01*
X65884Y389713D01*
X65746Y389671D01*
X65579Y389630D01*
X65427Y389561D01*
X65260Y389477D01*
X65246Y389463D01*
X65191Y389422D01*
X65121Y389366D01*
X65024Y389283D01*
X64927Y389172D01*
X64830Y389034D01*
X64733Y388881D01*
X64650Y388701D01*
X64636Y388673D01*
X64622Y388604D01*
X64594Y388493D01*
X64553Y388340D01*
X64511Y388132D01*
X64483Y387882D01*
X64470Y387591D01*
X64456Y387258D01*
Y383652D01*
X63277D01*
Y390615D01*
X64331D01*
Y389616D01*
X64345Y389644D01*
X64386Y389699D01*
X64470Y389796D01*
X64567Y389907D01*
X64692Y390046D01*
X64844Y390185D01*
X65010Y390323D01*
X65205Y390448D01*
X65232Y390462D01*
X65302Y390504D01*
X65413Y390545D01*
X65565Y390615D01*
X65746Y390670D01*
X65953Y390712D01*
X66189Y390753D01*
X66439Y390767D01*
X66564D01*
X66716Y390753D01*
X66883Y390725D01*
X67091Y390684D01*
X67299Y390628D01*
X67507Y390545D01*
X67701Y390434D01*
X67729Y390420D01*
X67784Y390379D01*
X67867Y390309D01*
X67978Y390198D01*
X68089Y390074D01*
X68214Y389921D01*
X68325Y389741D01*
X68408Y389533D01*
X68422Y389547D01*
X68450Y389588D01*
X68491Y389644D01*
X68561Y389727D01*
X68644Y389824D01*
X68741Y389921D01*
X68852Y390032D01*
X68991Y390157D01*
X69143Y390268D01*
X69296Y390379D01*
X69476Y390476D01*
X69670Y390573D01*
X69878Y390656D01*
X70100Y390712D01*
X70322Y390753D01*
X70572Y390767D01*
X70669D01*
X70738Y390753D01*
D02*
G37*
G36*
X25569Y383652D02*
X24348D01*
Y391682D01*
X21547Y383652D01*
X20410D01*
X17636Y391821D01*
Y383652D01*
X16416D01*
Y393250D01*
X18316D01*
X20590Y386440D01*
Y386426D01*
X20604Y386399D01*
X20618Y386357D01*
X20645Y386287D01*
X20701Y386121D01*
X20770Y385913D01*
X20840Y385677D01*
X20923Y385442D01*
X20992Y385220D01*
X21048Y385025D01*
X21061Y385053D01*
X21075Y385123D01*
X21117Y385247D01*
X21172Y385414D01*
X21242Y385636D01*
X21339Y385899D01*
X21436Y386204D01*
X21561Y386565D01*
X23863Y393250D01*
X25569D01*
Y383652D01*
D02*
G37*
G36*
X96367Y390753D02*
X96575Y390739D01*
X96811Y390712D01*
X97046Y390670D01*
X97282Y390615D01*
X97504Y390545D01*
X97532Y390531D01*
X97601Y390504D01*
X97698Y390462D01*
X97823Y390406D01*
X97962Y390323D01*
X98100Y390240D01*
X98225Y390129D01*
X98336Y390018D01*
X98350Y390004D01*
X98378Y389963D01*
X98419Y389893D01*
X98475Y389810D01*
X98544Y389685D01*
X98600Y389561D01*
X98655Y389408D01*
X98697Y389228D01*
Y389214D01*
X98711Y389172D01*
X98724Y389089D01*
X98738Y388978D01*
Y388825D01*
X98752Y388645D01*
X98766Y388409D01*
Y388146D01*
Y386565D01*
Y386551D01*
Y386496D01*
Y386412D01*
Y386301D01*
Y386177D01*
Y386024D01*
X98780Y385691D01*
Y385345D01*
X98794Y384998D01*
X98808Y384845D01*
Y384707D01*
X98822Y384582D01*
X98835Y384485D01*
Y384471D01*
X98849Y384415D01*
X98863Y384332D01*
X98905Y384221D01*
X98933Y384096D01*
X98988Y383958D01*
X99057Y383805D01*
X99127Y383653D01*
X97892D01*
X97879Y383666D01*
X97865Y383722D01*
X97837Y383791D01*
X97795Y383902D01*
X97754Y384027D01*
X97726Y384180D01*
X97698Y384346D01*
X97670Y384526D01*
X97657D01*
X97643Y384498D01*
X97560Y384429D01*
X97435Y384332D01*
X97268Y384207D01*
X97060Y384082D01*
X96852Y383944D01*
X96630Y383819D01*
X96395Y383722D01*
X96367Y383708D01*
X96284Y383694D01*
X96159Y383653D01*
X96006Y383611D01*
X95812Y383569D01*
X95590Y383542D01*
X95341Y383514D01*
X95091Y383500D01*
X94980D01*
X94897Y383514D01*
X94800D01*
X94689Y383528D01*
X94439Y383569D01*
X94162Y383639D01*
X93857Y383736D01*
X93579Y383875D01*
X93330Y384055D01*
X93302Y384082D01*
X93233Y384152D01*
X93136Y384277D01*
X93025Y384443D01*
X92914Y384651D01*
X92817Y384887D01*
X92747Y385178D01*
X92733Y385317D01*
X92719Y385483D01*
Y385511D01*
Y385566D01*
X92733Y385663D01*
X92747Y385788D01*
X92775Y385941D01*
X92817Y386093D01*
X92872Y386260D01*
X92941Y386412D01*
X92955Y386426D01*
X92983Y386482D01*
X93039Y386565D01*
X93108Y386662D01*
X93191Y386773D01*
X93302Y386884D01*
X93413Y386995D01*
X93552Y387092D01*
X93566Y387106D01*
X93621Y387133D01*
X93690Y387189D01*
X93801Y387244D01*
X93926Y387300D01*
X94079Y387369D01*
X94231Y387425D01*
X94411Y387480D01*
X94425D01*
X94481Y387494D01*
X94564Y387522D01*
X94675Y387536D01*
X94814Y387564D01*
X94994Y387591D01*
X95202Y387633D01*
X95452Y387660D01*
X95465D01*
X95521Y387674D01*
X95590D01*
X95687Y387688D01*
X95798Y387702D01*
X95937Y387730D01*
X96089Y387744D01*
X96256Y387771D01*
X96589Y387841D01*
X96949Y387910D01*
X97268Y387993D01*
X97421Y388035D01*
X97560Y388077D01*
Y388091D01*
Y388118D01*
X97573Y388201D01*
Y388298D01*
Y388354D01*
Y388382D01*
Y388396D01*
Y388409D01*
Y388493D01*
X97560Y388631D01*
X97532Y388784D01*
X97490Y388950D01*
X97421Y389117D01*
X97338Y389269D01*
X97227Y389394D01*
X97213Y389408D01*
X97143Y389463D01*
X97033Y389519D01*
X96894Y389602D01*
X96700Y389672D01*
X96478Y389741D01*
X96201Y389782D01*
X95882Y389796D01*
X95743D01*
X95604Y389782D01*
X95410Y389755D01*
X95216Y389727D01*
X95008Y389672D01*
X94814Y389602D01*
X94647Y389505D01*
X94633Y389491D01*
X94578Y389450D01*
X94508Y389380D01*
X94425Y389269D01*
X94342Y389131D01*
X94245Y388950D01*
X94162Y388728D01*
X94079Y388479D01*
X92928Y388631D01*
Y388645D01*
X92941Y388659D01*
Y388701D01*
X92955Y388756D01*
X92997Y388881D01*
X93052Y389061D01*
X93122Y389241D01*
X93205Y389436D01*
X93316Y389630D01*
X93441Y389810D01*
X93455Y389824D01*
X93510Y389879D01*
X93593Y389963D01*
X93704Y390074D01*
X93857Y390185D01*
X94037Y390295D01*
X94245Y390420D01*
X94481Y390517D01*
X94495D01*
X94508Y390531D01*
X94550Y390545D01*
X94606Y390559D01*
X94744Y390601D01*
X94938Y390642D01*
X95160Y390684D01*
X95438Y390726D01*
X95729Y390753D01*
X96062Y390767D01*
X96214D01*
X96367Y390753D01*
D02*
G37*
G36*
X59075Y390753D02*
X59283Y390739D01*
X59518Y390712D01*
X59754Y390670D01*
X59990Y390615D01*
X60212Y390545D01*
X60240Y390531D01*
X60309Y390504D01*
X60406Y390462D01*
X60531Y390406D01*
X60670Y390323D01*
X60808Y390240D01*
X60933Y390129D01*
X61044Y390018D01*
X61058Y390004D01*
X61086Y389963D01*
X61127Y389893D01*
X61183Y389810D01*
X61252Y389685D01*
X61308Y389561D01*
X61363Y389408D01*
X61405Y389228D01*
Y389214D01*
X61418Y389172D01*
X61432Y389089D01*
X61446Y388978D01*
Y388825D01*
X61460Y388645D01*
X61474Y388409D01*
Y388146D01*
Y386565D01*
Y386551D01*
Y386496D01*
Y386412D01*
Y386301D01*
Y386177D01*
Y386024D01*
X61488Y385691D01*
Y385345D01*
X61502Y384998D01*
X61516Y384845D01*
Y384706D01*
X61529Y384582D01*
X61543Y384485D01*
Y384471D01*
X61557Y384415D01*
X61571Y384332D01*
X61613Y384221D01*
X61640Y384096D01*
X61696Y383958D01*
X61765Y383805D01*
X61835Y383652D01*
X60600D01*
X60586Y383666D01*
X60573Y383722D01*
X60545Y383791D01*
X60503Y383902D01*
X60462Y384027D01*
X60434Y384179D01*
X60406Y384346D01*
X60378Y384526D01*
X60364D01*
X60351Y384498D01*
X60267Y384429D01*
X60143Y384332D01*
X59976Y384207D01*
X59768Y384082D01*
X59560Y383944D01*
X59338Y383819D01*
X59103Y383722D01*
X59075Y383708D01*
X58992Y383694D01*
X58867Y383652D01*
X58714Y383611D01*
X58520Y383569D01*
X58298Y383542D01*
X58049Y383514D01*
X57799Y383500D01*
X57688D01*
X57605Y383514D01*
X57508D01*
X57397Y383528D01*
X57147Y383569D01*
X56870Y383639D01*
X56565Y383736D01*
X56287Y383874D01*
X56038Y384055D01*
X56010Y384082D01*
X55940Y384152D01*
X55843Y384277D01*
X55732Y384443D01*
X55622Y384651D01*
X55525Y384887D01*
X55455Y385178D01*
X55441Y385317D01*
X55427Y385483D01*
Y385511D01*
Y385566D01*
X55441Y385663D01*
X55455Y385788D01*
X55483Y385941D01*
X55525Y386093D01*
X55580Y386260D01*
X55649Y386412D01*
X55663Y386426D01*
X55691Y386482D01*
X55746Y386565D01*
X55816Y386662D01*
X55899Y386773D01*
X56010Y386884D01*
X56121Y386995D01*
X56259Y387092D01*
X56273Y387106D01*
X56329Y387133D01*
X56398Y387189D01*
X56509Y387244D01*
X56634Y387300D01*
X56786Y387369D01*
X56939Y387425D01*
X57119Y387480D01*
X57133D01*
X57189Y387494D01*
X57272Y387522D01*
X57383Y387536D01*
X57522Y387563D01*
X57702Y387591D01*
X57910Y387633D01*
X58159Y387660D01*
X58173D01*
X58229Y387674D01*
X58298D01*
X58395Y387688D01*
X58506Y387702D01*
X58645Y387730D01*
X58797Y387744D01*
X58964Y387771D01*
X59297Y387841D01*
X59657Y387910D01*
X59976Y387993D01*
X60129Y388035D01*
X60267Y388077D01*
Y388090D01*
Y388118D01*
X60281Y388201D01*
Y388298D01*
Y388354D01*
Y388382D01*
Y388396D01*
Y388409D01*
Y388493D01*
X60267Y388631D01*
X60240Y388784D01*
X60198Y388950D01*
X60129Y389117D01*
X60045Y389269D01*
X59935Y389394D01*
X59921Y389408D01*
X59851Y389463D01*
X59740Y389519D01*
X59602Y389602D01*
X59408Y389671D01*
X59186Y389741D01*
X58908Y389782D01*
X58589Y389796D01*
X58451D01*
X58312Y389782D01*
X58118Y389755D01*
X57924Y389727D01*
X57716Y389671D01*
X57522Y389602D01*
X57355Y389505D01*
X57341Y389491D01*
X57286Y389450D01*
X57216Y389380D01*
X57133Y389269D01*
X57050Y389131D01*
X56953Y388950D01*
X56870Y388728D01*
X56786Y388479D01*
X55635Y388631D01*
Y388645D01*
X55649Y388659D01*
Y388701D01*
X55663Y388756D01*
X55705Y388881D01*
X55760Y389061D01*
X55830Y389241D01*
X55913Y389436D01*
X56024Y389630D01*
X56149Y389810D01*
X56162Y389824D01*
X56218Y389879D01*
X56301Y389963D01*
X56412Y390074D01*
X56565Y390185D01*
X56745Y390295D01*
X56953Y390420D01*
X57189Y390517D01*
X57203D01*
X57216Y390531D01*
X57258Y390545D01*
X57313Y390559D01*
X57452Y390601D01*
X57646Y390642D01*
X57868Y390684D01*
X58146Y390725D01*
X58437Y390753D01*
X58770Y390767D01*
X58922D01*
X59075Y390753D01*
D02*
G37*
G36*
X49741Y384790D02*
X54471D01*
Y383652D01*
X48465D01*
Y393250D01*
X49741D01*
Y384790D01*
D02*
G37*
G36*
X31643Y387771D02*
X34431Y390615D01*
X35970D01*
X33293Y388021D01*
X36233Y383652D01*
X34777D01*
X32461Y387203D01*
X31643Y386412D01*
Y383652D01*
X30464D01*
Y393250D01*
X31643D01*
Y387771D01*
D02*
G37*
G36*
X28661Y383652D02*
X27483D01*
Y390615D01*
X28661D01*
Y383652D01*
D02*
G37*
G36*
X90764Y390615D02*
X91957D01*
Y389699D01*
X90764D01*
Y385608D01*
Y385580D01*
Y385525D01*
Y385442D01*
X90778Y385345D01*
X90792Y385123D01*
X90806Y385025D01*
X90820Y384956D01*
X90833Y384929D01*
X90875Y384873D01*
X90931Y384804D01*
X91028Y384734D01*
X91055Y384720D01*
X91125Y384693D01*
X91249Y384665D01*
X91430Y384651D01*
X91568D01*
X91638Y384665D01*
X91735D01*
X91846Y384679D01*
X91957Y384693D01*
X92109Y383653D01*
X92082D01*
X92026Y383639D01*
X91929Y383625D01*
X91804Y383611D01*
X91665Y383583D01*
X91513Y383569D01*
X91208Y383555D01*
X91097D01*
X90986Y383569D01*
X90847Y383583D01*
X90681Y383597D01*
X90514Y383639D01*
X90362Y383680D01*
X90209Y383750D01*
X90196Y383764D01*
X90154Y383791D01*
X90098Y383833D01*
X90015Y383902D01*
X89946Y383971D01*
X89863Y384069D01*
X89779Y384166D01*
X89724Y384291D01*
Y384304D01*
X89696Y384360D01*
X89682Y384457D01*
X89655Y384596D01*
X89627Y384776D01*
X89613Y384887D01*
Y385012D01*
X89599Y385164D01*
X89585Y385317D01*
Y385483D01*
Y385677D01*
Y389699D01*
X88712Y389699D01*
Y390615D01*
X89585Y390615D01*
Y392334D01*
X90764Y393041D01*
Y390615D01*
D02*
G37*
G36*
X85009Y390753D02*
X85120Y390739D01*
X85258Y390712D01*
X85411Y390684D01*
X85591Y390642D01*
X85758Y390601D01*
X85952Y390531D01*
X86132Y390462D01*
X86326Y390365D01*
X86520Y390254D01*
X86714Y390129D01*
X86895Y389977D01*
X87061Y389810D01*
X87075Y389796D01*
X87103Y389768D01*
X87144Y389713D01*
X87200Y389630D01*
X87269Y389533D01*
X87339Y389422D01*
X87422Y389283D01*
X87505Y389117D01*
X87588Y388936D01*
X87671Y388742D01*
X87741Y388520D01*
X87810Y388285D01*
X87866Y388021D01*
X87907Y387744D01*
X87935Y387453D01*
X87949Y387133D01*
Y387120D01*
Y387064D01*
Y386967D01*
X87935Y386828D01*
X82734D01*
Y386814D01*
Y386773D01*
X82748Y386717D01*
Y386634D01*
X82762Y386537D01*
X82790Y386426D01*
X82831Y386177D01*
X82914Y385899D01*
X83026Y385594D01*
X83178Y385317D01*
X83372Y385067D01*
X83386D01*
X83400Y385039D01*
X83483Y384970D01*
X83608Y384873D01*
X83774Y384776D01*
X83996Y384665D01*
X84246Y384568D01*
X84523Y384498D01*
X84676Y384485D01*
X84842Y384471D01*
X84953D01*
X85078Y384485D01*
X85231Y384512D01*
X85397Y384554D01*
X85591Y384609D01*
X85771Y384693D01*
X85952Y384804D01*
X85966Y384818D01*
X86035Y384873D01*
X86118Y384956D01*
X86215Y385067D01*
X86326Y385220D01*
X86451Y385414D01*
X86576Y385636D01*
X86687Y385899D01*
X87907Y385747D01*
Y385733D01*
X87893Y385705D01*
X87879Y385650D01*
X87852Y385566D01*
X87810Y385483D01*
X87768Y385372D01*
X87657Y385136D01*
X87519Y384873D01*
X87325Y384596D01*
X87103Y384332D01*
X86825Y384082D01*
X86812D01*
X86784Y384055D01*
X86742Y384027D01*
X86687Y383985D01*
X86603Y383944D01*
X86520Y383902D01*
X86409Y383847D01*
X86285Y383791D01*
X86146Y383736D01*
X86007Y383680D01*
X85660Y383597D01*
X85272Y383528D01*
X84842Y383500D01*
X84690D01*
X84593Y383514D01*
X84468Y383528D01*
X84315Y383555D01*
X84149Y383583D01*
X83968Y383611D01*
X83580Y383722D01*
X83372Y383805D01*
X83178Y383888D01*
X82970Y383999D01*
X82776Y384124D01*
X82596Y384263D01*
X82415Y384429D01*
X82401Y384443D01*
X82374Y384471D01*
X82332Y384526D01*
X82277Y384609D01*
X82207Y384706D01*
X82138Y384818D01*
X82055Y384956D01*
X81972Y385109D01*
X81888Y385289D01*
X81805Y385483D01*
X81736Y385705D01*
X81666Y385941D01*
X81611Y386190D01*
X81569Y386468D01*
X81542Y386759D01*
X81528Y387064D01*
Y387078D01*
Y387147D01*
Y387231D01*
X81542Y387355D01*
X81555Y387508D01*
X81569Y387674D01*
X81597Y387868D01*
X81639Y388063D01*
X81750Y388507D01*
X81819Y388728D01*
X81902Y388964D01*
X82013Y389186D01*
X82138Y389394D01*
X82277Y389602D01*
X82429Y389796D01*
X82443Y389810D01*
X82471Y389838D01*
X82526Y389879D01*
X82596Y389949D01*
X82679Y390018D01*
X82790Y390101D01*
X82914Y390198D01*
X83067Y390282D01*
X83220Y390379D01*
X83400Y390462D01*
X83594Y390545D01*
X83802Y390615D01*
X84024Y390684D01*
X84260Y390725D01*
X84509Y390753D01*
X84773Y390767D01*
X84912D01*
X85009Y390753D01*
D02*
G37*
G36*
X75620Y389824D02*
X75634Y389838D01*
X75648Y389866D01*
X75689Y389907D01*
X75758Y389977D01*
X75828Y390046D01*
X75911Y390129D01*
X76022Y390212D01*
X76133Y390295D01*
X76410Y390476D01*
X76729Y390615D01*
X76909Y390684D01*
X77104Y390725D01*
X77312Y390753D01*
X77520Y390767D01*
X77631D01*
X77755Y390753D01*
X77908Y390739D01*
X78088Y390698D01*
X78296Y390656D01*
X78518Y390587D01*
X78726Y390504D01*
X78754Y390490D01*
X78823Y390462D01*
X78934Y390393D01*
X79059Y390309D01*
X79212Y390212D01*
X79364Y390088D01*
X79531Y389935D01*
X79669Y389768D01*
X79683Y389755D01*
X79725Y389685D01*
X79794Y389588D01*
X79877Y389463D01*
X79974Y389297D01*
X80071Y389103D01*
X80169Y388881D01*
X80252Y388645D01*
Y388631D01*
X80266Y388617D01*
X80280Y388576D01*
X80293Y388534D01*
X80321Y388396D01*
X80363Y388215D01*
X80404Y388007D01*
X80446Y387771D01*
X80460Y387508D01*
X80474Y387231D01*
Y387217D01*
Y387147D01*
Y387064D01*
X80460Y386939D01*
X80446Y386787D01*
X80432Y386620D01*
X80404Y386426D01*
X80363Y386218D01*
X80252Y385774D01*
X80183Y385539D01*
X80099Y385317D01*
X80002Y385081D01*
X79877Y384873D01*
X79739Y384665D01*
X79586Y384471D01*
X79572Y384457D01*
X79545Y384429D01*
X79503Y384388D01*
X79434Y384318D01*
X79337Y384249D01*
X79239Y384166D01*
X79128Y384082D01*
X78990Y383985D01*
X78837Y383902D01*
X78685Y383805D01*
X78310Y383652D01*
X78116Y383583D01*
X77908Y383542D01*
X77686Y383514D01*
X77464Y383500D01*
X77409D01*
X77339Y383514D01*
X77256D01*
X77159Y383528D01*
X77034Y383555D01*
X76757Y383625D01*
X76604Y383680D01*
X76452Y383750D01*
X76285Y383833D01*
X76133Y383930D01*
X75967Y384055D01*
X75814Y384193D01*
X75675Y384346D01*
X75537Y384526D01*
Y383652D01*
X74441D01*
Y393250D01*
X75620D01*
Y389824D01*
D02*
G37*
G36*
X40255Y390753D02*
X40366Y390739D01*
X40505Y390712D01*
X40658Y390684D01*
X40838Y390642D01*
X41004Y390601D01*
X41198Y390531D01*
X41379Y390462D01*
X41573Y390365D01*
X41767Y390254D01*
X41961Y390129D01*
X42141Y389977D01*
X42308Y389810D01*
X42322Y389796D01*
X42350Y389768D01*
X42391Y389713D01*
X42446Y389630D01*
X42516Y389533D01*
X42585Y389422D01*
X42668Y389283D01*
X42752Y389117D01*
X42835Y388936D01*
X42918Y388742D01*
X42987Y388520D01*
X43057Y388285D01*
X43112Y388021D01*
X43154Y387744D01*
X43182Y387453D01*
X43195Y387133D01*
Y387120D01*
Y387064D01*
Y386967D01*
X43182Y386828D01*
X37981D01*
Y386814D01*
Y386773D01*
X37995Y386717D01*
Y386634D01*
X38009Y386537D01*
X38036Y386426D01*
X38078Y386177D01*
X38161Y385899D01*
X38272Y385594D01*
X38425Y385317D01*
X38619Y385067D01*
X38633D01*
X38647Y385039D01*
X38730Y384970D01*
X38855Y384873D01*
X39021Y384776D01*
X39243Y384665D01*
X39493Y384568D01*
X39770Y384498D01*
X39922Y384485D01*
X40089Y384471D01*
X40200D01*
X40325Y384485D01*
X40477Y384512D01*
X40644Y384554D01*
X40838Y384609D01*
X41018Y384693D01*
X41198Y384804D01*
X41212Y384818D01*
X41282Y384873D01*
X41365Y384956D01*
X41462Y385067D01*
X41573Y385220D01*
X41698Y385414D01*
X41823Y385636D01*
X41933Y385899D01*
X43154Y385747D01*
Y385733D01*
X43140Y385705D01*
X43126Y385650D01*
X43098Y385566D01*
X43057Y385483D01*
X43015Y385372D01*
X42904Y385136D01*
X42765Y384873D01*
X42571Y384596D01*
X42350Y384332D01*
X42072Y384082D01*
X42058D01*
X42031Y384055D01*
X41989Y384027D01*
X41933Y383985D01*
X41850Y383944D01*
X41767Y383902D01*
X41656Y383847D01*
X41531Y383791D01*
X41393Y383736D01*
X41254Y383680D01*
X40907Y383597D01*
X40519Y383528D01*
X40089Y383500D01*
X39936D01*
X39839Y383514D01*
X39715Y383528D01*
X39562Y383555D01*
X39395Y383583D01*
X39215Y383611D01*
X38827Y383722D01*
X38619Y383805D01*
X38425Y383888D01*
X38217Y383999D01*
X38022Y384124D01*
X37842Y384263D01*
X37662Y384429D01*
X37648Y384443D01*
X37620Y384471D01*
X37579Y384526D01*
X37523Y384609D01*
X37454Y384706D01*
X37385Y384818D01*
X37301Y384956D01*
X37218Y385109D01*
X37135Y385289D01*
X37052Y385483D01*
X36982Y385705D01*
X36913Y385941D01*
X36858Y386190D01*
X36816Y386468D01*
X36788Y386759D01*
X36774Y387064D01*
Y387078D01*
Y387147D01*
Y387231D01*
X36788Y387355D01*
X36802Y387508D01*
X36816Y387674D01*
X36844Y387868D01*
X36885Y388063D01*
X36996Y388507D01*
X37066Y388728D01*
X37149Y388964D01*
X37260Y389186D01*
X37385Y389394D01*
X37523Y389602D01*
X37676Y389796D01*
X37690Y389810D01*
X37717Y389838D01*
X37773Y389879D01*
X37842Y389949D01*
X37926Y390018D01*
X38036Y390101D01*
X38161Y390198D01*
X38314Y390282D01*
X38466Y390379D01*
X38647Y390462D01*
X38841Y390545D01*
X39049Y390615D01*
X39271Y390684D01*
X39506Y390725D01*
X39756Y390753D01*
X40020Y390767D01*
X40158D01*
X40255Y390753D01*
D02*
G37*
G36*
X105539Y376317D02*
X104360D01*
Y377662D01*
X105539D01*
Y376317D01*
D02*
G37*
G36*
X51036Y368065D02*
X49940D01*
Y368939D01*
X49926Y368925D01*
X49913Y368897D01*
X49871Y368842D01*
X49815Y368773D01*
X49746Y368703D01*
X49663Y368620D01*
X49566Y368523D01*
X49441Y368426D01*
X49316Y368329D01*
X49177Y368232D01*
X49011Y368148D01*
X48831Y368079D01*
X48650Y368010D01*
X48443Y367954D01*
X48221Y367927D01*
X47985Y367913D01*
X47902D01*
X47846Y367927D01*
X47680Y367940D01*
X47486Y367968D01*
X47250Y368024D01*
X46986Y368107D01*
X46723Y368218D01*
X46459Y368370D01*
X46445D01*
X46432Y368398D01*
X46348Y368454D01*
X46224Y368564D01*
X46071Y368703D01*
X45891Y368884D01*
X45710Y369105D01*
X45530Y369355D01*
X45378Y369646D01*
Y369660D01*
X45364Y369688D01*
X45350Y369729D01*
X45322Y369785D01*
X45294Y369868D01*
X45253Y369965D01*
X45225Y370062D01*
X45197Y370187D01*
X45128Y370465D01*
X45059Y370784D01*
X45017Y371144D01*
X45003Y371532D01*
Y371546D01*
Y371574D01*
Y371629D01*
Y371713D01*
X45017Y371796D01*
Y371907D01*
X45045Y372156D01*
X45086Y372448D01*
X45156Y372767D01*
X45239Y373100D01*
X45350Y373419D01*
Y373432D01*
X45364Y373460D01*
X45391Y373502D01*
X45419Y373557D01*
X45502Y373710D01*
X45613Y373904D01*
X45752Y374112D01*
X45932Y374320D01*
X46140Y374542D01*
X46390Y374722D01*
X46404D01*
X46418Y374736D01*
X46459Y374764D01*
X46515Y374791D01*
X46653Y374861D01*
X46848Y374958D01*
X47070Y375041D01*
X47333Y375110D01*
X47624Y375166D01*
X47929Y375180D01*
X48040D01*
X48151Y375166D01*
X48304Y375152D01*
X48484Y375110D01*
X48678Y375069D01*
X48872Y375000D01*
X49053Y374902D01*
X49080Y374888D01*
X49136Y374861D01*
X49219Y374791D01*
X49330Y374722D01*
X49469Y374625D01*
X49594Y374500D01*
X49732Y374375D01*
X49857Y374223D01*
Y377662D01*
X51036D01*
Y368065D01*
D02*
G37*
G36*
X34255Y375166D02*
X34352D01*
X34449Y375152D01*
X34685Y375110D01*
X34935Y375041D01*
X35198Y374930D01*
X35462Y374791D01*
X35684Y374597D01*
X35711Y374570D01*
X35767Y374486D01*
X35864Y374361D01*
X35905Y374264D01*
X35961Y374167D01*
X36016Y374043D01*
X36058Y373918D01*
X36114Y373779D01*
X36155Y373613D01*
X36183Y373446D01*
X36210Y373252D01*
X36238Y373058D01*
Y372836D01*
Y368065D01*
X35059D01*
Y372434D01*
Y372448D01*
Y372462D01*
Y372545D01*
Y372670D01*
X35046Y372822D01*
X35032Y372989D01*
X35018Y373155D01*
X34990Y373321D01*
X34948Y373446D01*
Y373460D01*
X34921Y373502D01*
X34893Y373557D01*
X34851Y373627D01*
X34796Y373710D01*
X34727Y373793D01*
X34643Y373876D01*
X34532Y373959D01*
X34519Y373973D01*
X34477Y373987D01*
X34422Y374015D01*
X34324Y374056D01*
X34227Y374098D01*
X34102Y374126D01*
X33978Y374140D01*
X33825Y374154D01*
X33756D01*
X33700Y374140D01*
X33562Y374126D01*
X33395Y374098D01*
X33201Y374029D01*
X32993Y373946D01*
X32785Y373821D01*
X32591Y373654D01*
X32577Y373627D01*
X32522Y373557D01*
X32438Y373446D01*
X32355Y373280D01*
X32258Y373058D01*
X32189Y372794D01*
X32133Y372475D01*
X32106Y372101D01*
Y368065D01*
X30927D01*
Y372573D01*
Y372586D01*
Y372614D01*
Y372642D01*
Y372697D01*
X30913Y372850D01*
X30885Y373016D01*
X30857Y373210D01*
X30802Y373405D01*
X30733Y373585D01*
X30635Y373751D01*
X30622Y373765D01*
X30580Y373821D01*
X30511Y373876D01*
X30414Y373959D01*
X30289Y374029D01*
X30122Y374098D01*
X29928Y374140D01*
X29692Y374154D01*
X29609D01*
X29512Y374140D01*
X29401Y374126D01*
X29262Y374084D01*
X29096Y374043D01*
X28944Y373973D01*
X28777Y373890D01*
X28763Y373876D01*
X28708Y373834D01*
X28638Y373779D01*
X28541Y373696D01*
X28444Y373585D01*
X28347Y373446D01*
X28250Y373294D01*
X28167Y373113D01*
X28153Y373086D01*
X28139Y373016D01*
X28111Y372905D01*
X28070Y372753D01*
X28028Y372545D01*
X28001Y372295D01*
X27987Y372004D01*
X27973Y371671D01*
Y368065D01*
X26794D01*
Y375027D01*
X27848D01*
Y374029D01*
X27862Y374056D01*
X27903Y374112D01*
X27987Y374209D01*
X28084Y374320D01*
X28208Y374459D01*
X28361Y374597D01*
X28528Y374736D01*
X28722Y374861D01*
X28749Y374875D01*
X28819Y374916D01*
X28930Y374958D01*
X29082Y375027D01*
X29262Y375083D01*
X29471Y375124D01*
X29706Y375166D01*
X29956Y375180D01*
X30081D01*
X30233Y375166D01*
X30400Y375138D01*
X30608Y375097D01*
X30816Y375041D01*
X31024Y374958D01*
X31218Y374847D01*
X31246Y374833D01*
X31301Y374791D01*
X31384Y374722D01*
X31495Y374611D01*
X31606Y374486D01*
X31731Y374334D01*
X31842Y374154D01*
X31925Y373946D01*
X31939Y373959D01*
X31967Y374001D01*
X32008Y374056D01*
X32078Y374140D01*
X32161Y374237D01*
X32258Y374334D01*
X32369Y374445D01*
X32508Y374570D01*
X32660Y374680D01*
X32813Y374791D01*
X32993Y374888D01*
X33187Y374986D01*
X33395Y375069D01*
X33617Y375124D01*
X33839Y375166D01*
X34089Y375180D01*
X34186D01*
X34255Y375166D01*
D02*
G37*
G36*
X101170Y368065D02*
X99964D01*
X98854Y372226D01*
X98577Y373419D01*
X97176Y368065D01*
X95928D01*
X93820Y375027D01*
X95054D01*
X96164Y371005D01*
X96552Y369508D01*
Y369521D01*
X96566Y369549D01*
X96580Y369619D01*
X96594Y369660D01*
X96607Y369729D01*
X96621Y369813D01*
X96649Y369910D01*
X96677Y370021D01*
X96718Y370159D01*
X96760Y370312D01*
X96802Y370492D01*
X96857Y370700D01*
X96912Y370936D01*
X98022Y375027D01*
X99229D01*
X100269Y370978D01*
X100615Y369646D01*
X101018Y370992D01*
X102210Y375027D01*
X103361D01*
X101170Y368065D01*
D02*
G37*
G36*
X68635Y367954D02*
Y367940D01*
X68621Y367899D01*
X68593Y367843D01*
X68566Y367774D01*
X68524Y367677D01*
X68482Y367566D01*
X68385Y367330D01*
X68288Y367067D01*
X68177Y366803D01*
X68066Y366567D01*
X68011Y366470D01*
X67969Y366373D01*
X67955Y366346D01*
X67914Y366276D01*
X67844Y366179D01*
X67761Y366054D01*
X67650Y365916D01*
X67525Y365777D01*
X67401Y365638D01*
X67248Y365527D01*
X67234Y365513D01*
X67179Y365486D01*
X67095Y365444D01*
X66971Y365389D01*
X66832Y365333D01*
X66666Y365292D01*
X66485Y365264D01*
X66277Y365250D01*
X66222D01*
X66152Y365264D01*
X66055D01*
X65944Y365292D01*
X65820Y365319D01*
X65681Y365347D01*
X65528Y365402D01*
X65403Y366498D01*
X65417D01*
X65473Y366484D01*
X65542Y366470D01*
X65625Y366443D01*
X65847Y366401D01*
X66069Y366387D01*
X66139D01*
X66208Y366401D01*
X66291D01*
X66499Y366443D01*
X66596Y366484D01*
X66693Y366526D01*
X66707D01*
X66735Y366554D01*
X66776Y366581D01*
X66832Y366623D01*
X66957Y366734D01*
X67068Y366886D01*
Y366900D01*
X67095Y366928D01*
X67123Y366983D01*
X67151Y367067D01*
X67206Y367178D01*
X67262Y367344D01*
X67345Y367538D01*
X67428Y367774D01*
Y367788D01*
X67456Y367843D01*
X67484Y367940D01*
X67539Y368065D01*
X64904Y375027D01*
X66152D01*
X67609Y370992D01*
Y370978D01*
X67622Y370964D01*
X67636Y370922D01*
X67650Y370853D01*
X67678Y370784D01*
X67706Y370700D01*
X67775Y370506D01*
X67858Y370270D01*
X67941Y369993D01*
X68025Y369702D01*
X68108Y369383D01*
Y369397D01*
X68122Y369424D01*
X68136Y369466D01*
X68149Y369521D01*
X68163Y369591D01*
X68191Y369674D01*
X68246Y369882D01*
X68316Y370118D01*
X68413Y370395D01*
X68496Y370672D01*
X68607Y370964D01*
X70105Y375027D01*
X71284D01*
X68635Y367954D01*
D02*
G37*
G36*
X105539Y368065D02*
X104360D01*
Y375027D01*
X105539D01*
Y368065D01*
D02*
G37*
G36*
X75541Y375166D02*
X75749Y375152D01*
X75985Y375124D01*
X76221Y375083D01*
X76457Y375027D01*
X76679Y374958D01*
X76706Y374944D01*
X76776Y374916D01*
X76873Y374875D01*
X76997Y374819D01*
X77136Y374736D01*
X77275Y374653D01*
X77400Y374542D01*
X77511Y374431D01*
X77524Y374417D01*
X77552Y374375D01*
X77594Y374306D01*
X77649Y374223D01*
X77719Y374098D01*
X77774Y373973D01*
X77830Y373821D01*
X77871Y373640D01*
Y373627D01*
X77885Y373585D01*
X77899Y373502D01*
X77913Y373391D01*
Y373238D01*
X77927Y373058D01*
X77941Y372822D01*
Y372559D01*
Y370978D01*
Y370964D01*
Y370908D01*
Y370825D01*
Y370714D01*
Y370589D01*
Y370437D01*
X77954Y370104D01*
Y369757D01*
X77968Y369411D01*
X77982Y369258D01*
Y369119D01*
X77996Y368994D01*
X78010Y368897D01*
Y368884D01*
X78024Y368828D01*
X78038Y368745D01*
X78079Y368634D01*
X78107Y368509D01*
X78162Y368370D01*
X78232Y368218D01*
X78301Y368065D01*
X77067D01*
X77053Y368079D01*
X77039Y368135D01*
X77011Y368204D01*
X76970Y368315D01*
X76928Y368440D01*
X76900Y368592D01*
X76873Y368759D01*
X76845Y368939D01*
X76831D01*
X76817Y368911D01*
X76734Y368842D01*
X76609Y368745D01*
X76443Y368620D01*
X76235Y368495D01*
X76027Y368357D01*
X75805Y368232D01*
X75569Y368135D01*
X75541Y368121D01*
X75458Y368107D01*
X75333Y368065D01*
X75181Y368024D01*
X74987Y367982D01*
X74765Y367954D01*
X74515Y367927D01*
X74265Y367913D01*
X74155D01*
X74071Y367927D01*
X73974D01*
X73863Y367940D01*
X73614Y367982D01*
X73336Y368051D01*
X73031Y368148D01*
X72754Y368287D01*
X72504Y368467D01*
X72476Y368495D01*
X72407Y368564D01*
X72310Y368689D01*
X72199Y368856D01*
X72088Y369064D01*
X71991Y369300D01*
X71922Y369591D01*
X71908Y369729D01*
X71894Y369896D01*
Y369924D01*
Y369979D01*
X71908Y370076D01*
X71922Y370201D01*
X71949Y370354D01*
X71991Y370506D01*
X72046Y370672D01*
X72116Y370825D01*
X72130Y370839D01*
X72157Y370894D01*
X72213Y370978D01*
X72282Y371075D01*
X72365Y371186D01*
X72476Y371297D01*
X72587Y371408D01*
X72726Y371505D01*
X72740Y371519D01*
X72795Y371546D01*
X72865Y371602D01*
X72976Y371657D01*
X73101Y371713D01*
X73253Y371782D01*
X73406Y371838D01*
X73586Y371893D01*
X73600D01*
X73655Y371907D01*
X73738Y371935D01*
X73849Y371948D01*
X73988Y371976D01*
X74168Y372004D01*
X74376Y372046D01*
X74626Y372073D01*
X74640D01*
X74695Y372087D01*
X74765D01*
X74862Y372101D01*
X74973Y372115D01*
X75111Y372143D01*
X75264Y372156D01*
X75430Y372184D01*
X75763Y372253D01*
X76124Y372323D01*
X76443Y372406D01*
X76595Y372448D01*
X76734Y372489D01*
Y372503D01*
Y372531D01*
X76748Y372614D01*
Y372711D01*
Y372767D01*
Y372794D01*
Y372808D01*
Y372822D01*
Y372905D01*
X76734Y373044D01*
X76706Y373197D01*
X76665Y373363D01*
X76595Y373529D01*
X76512Y373682D01*
X76401Y373807D01*
X76387Y373821D01*
X76318Y373876D01*
X76207Y373932D01*
X76068Y374015D01*
X75874Y374084D01*
X75652Y374154D01*
X75375Y374195D01*
X75056Y374209D01*
X74917D01*
X74779Y374195D01*
X74584Y374167D01*
X74390Y374140D01*
X74182Y374084D01*
X73988Y374015D01*
X73822Y373918D01*
X73808Y373904D01*
X73752Y373862D01*
X73683Y373793D01*
X73600Y373682D01*
X73517Y373543D01*
X73419Y373363D01*
X73336Y373141D01*
X73253Y372892D01*
X72102Y373044D01*
Y373058D01*
X72116Y373072D01*
Y373113D01*
X72130Y373169D01*
X72171Y373294D01*
X72227Y373474D01*
X72296Y373654D01*
X72379Y373848D01*
X72490Y374043D01*
X72615Y374223D01*
X72629Y374237D01*
X72684Y374292D01*
X72768Y374375D01*
X72879Y374486D01*
X73031Y374597D01*
X73211Y374708D01*
X73419Y374833D01*
X73655Y374930D01*
X73669D01*
X73683Y374944D01*
X73725Y374958D01*
X73780Y374972D01*
X73919Y375013D01*
X74113Y375055D01*
X74335Y375097D01*
X74612Y375138D01*
X74903Y375166D01*
X75236Y375180D01*
X75389D01*
X75541Y375166D01*
D02*
G37*
G36*
X60605Y377648D02*
X60716D01*
X60966Y377621D01*
X61243Y377593D01*
X61534Y377537D01*
X61825Y377468D01*
X62089Y377371D01*
X62103D01*
X62117Y377357D01*
X62200Y377315D01*
X62325Y377246D01*
X62463Y377149D01*
X62630Y377024D01*
X62810Y376872D01*
X62977Y376678D01*
X63129Y376469D01*
X63143Y376442D01*
X63185Y376359D01*
X63254Y376248D01*
X63323Y376081D01*
X63393Y375887D01*
X63462Y375679D01*
X63504Y375443D01*
X63517Y375207D01*
Y375180D01*
Y375110D01*
X63504Y374986D01*
X63476Y374833D01*
X63434Y374653D01*
X63365Y374459D01*
X63282Y374264D01*
X63171Y374056D01*
X63157Y374029D01*
X63115Y373973D01*
X63032Y373862D01*
X62921Y373751D01*
X62782Y373613D01*
X62616Y373460D01*
X62408Y373321D01*
X62172Y373183D01*
X62186D01*
X62214Y373169D01*
X62255Y373155D01*
X62311Y373127D01*
X62477Y373072D01*
X62671Y372975D01*
X62880Y372850D01*
X63115Y372697D01*
X63323Y372517D01*
X63517Y372295D01*
X63531Y372267D01*
X63587Y372184D01*
X63670Y372059D01*
X63753Y371893D01*
X63836Y371671D01*
X63920Y371435D01*
X63975Y371158D01*
X63989Y370853D01*
Y370839D01*
Y370825D01*
Y370742D01*
X63975Y370603D01*
X63947Y370437D01*
X63920Y370243D01*
X63864Y370035D01*
X63795Y369813D01*
X63698Y369591D01*
X63684Y369563D01*
X63642Y369494D01*
X63587Y369397D01*
X63504Y369258D01*
X63393Y369119D01*
X63282Y368967D01*
X63143Y368814D01*
X62990Y368689D01*
X62977Y368675D01*
X62921Y368634D01*
X62824Y368578D01*
X62699Y368523D01*
X62547Y368440D01*
X62366Y368357D01*
X62172Y368287D01*
X61936Y368218D01*
X61909D01*
X61825Y368190D01*
X61687Y368176D01*
X61507Y368148D01*
X61285Y368121D01*
X61021Y368093D01*
X60730Y368079D01*
X60397Y368065D01*
X56736D01*
Y377662D01*
X60508D01*
X60605Y377648D01*
D02*
G37*
G36*
X41231Y375166D02*
X41439Y375152D01*
X41675Y375124D01*
X41911Y375083D01*
X42146Y375027D01*
X42368Y374958D01*
X42396Y374944D01*
X42465Y374916D01*
X42562Y374875D01*
X42687Y374819D01*
X42826Y374736D01*
X42965Y374653D01*
X43089Y374542D01*
X43200Y374431D01*
X43214Y374417D01*
X43242Y374375D01*
X43283Y374306D01*
X43339Y374223D01*
X43408Y374098D01*
X43464Y373973D01*
X43519Y373821D01*
X43561Y373640D01*
Y373627D01*
X43575Y373585D01*
X43589Y373502D01*
X43602Y373391D01*
Y373238D01*
X43616Y373058D01*
X43630Y372822D01*
Y372559D01*
Y370978D01*
Y370964D01*
Y370908D01*
Y370825D01*
Y370714D01*
Y370589D01*
Y370437D01*
X43644Y370104D01*
Y369757D01*
X43658Y369411D01*
X43672Y369258D01*
Y369119D01*
X43686Y368994D01*
X43699Y368897D01*
Y368884D01*
X43713Y368828D01*
X43727Y368745D01*
X43769Y368634D01*
X43797Y368509D01*
X43852Y368370D01*
X43921Y368218D01*
X43991Y368065D01*
X42756D01*
X42743Y368079D01*
X42729Y368135D01*
X42701Y368204D01*
X42659Y368315D01*
X42618Y368440D01*
X42590Y368592D01*
X42562Y368759D01*
X42534Y368939D01*
X42521D01*
X42507Y368911D01*
X42424Y368842D01*
X42299Y368745D01*
X42132Y368620D01*
X41924Y368495D01*
X41716Y368357D01*
X41494Y368232D01*
X41259Y368135D01*
X41231Y368121D01*
X41148Y368107D01*
X41023Y368065D01*
X40870Y368024D01*
X40676Y367982D01*
X40454Y367954D01*
X40205Y367927D01*
X39955Y367913D01*
X39844D01*
X39761Y367927D01*
X39664D01*
X39553Y367940D01*
X39303Y367982D01*
X39026Y368051D01*
X38721Y368148D01*
X38443Y368287D01*
X38194Y368467D01*
X38166Y368495D01*
X38097Y368564D01*
X38000Y368689D01*
X37889Y368856D01*
X37778Y369064D01*
X37681Y369300D01*
X37611Y369591D01*
X37597Y369729D01*
X37583Y369896D01*
Y369924D01*
Y369979D01*
X37597Y370076D01*
X37611Y370201D01*
X37639Y370354D01*
X37681Y370506D01*
X37736Y370672D01*
X37805Y370825D01*
X37819Y370839D01*
X37847Y370894D01*
X37903Y370978D01*
X37972Y371075D01*
X38055Y371186D01*
X38166Y371297D01*
X38277Y371408D01*
X38416Y371505D01*
X38430Y371519D01*
X38485Y371546D01*
X38554Y371602D01*
X38665Y371657D01*
X38790Y371713D01*
X38943Y371782D01*
X39095Y371838D01*
X39276Y371893D01*
X39289D01*
X39345Y371907D01*
X39428Y371935D01*
X39539Y371948D01*
X39678Y371976D01*
X39858Y372004D01*
X40066Y372046D01*
X40316Y372073D01*
X40329D01*
X40385Y372087D01*
X40454D01*
X40551Y372101D01*
X40662Y372115D01*
X40801Y372143D01*
X40953Y372156D01*
X41120Y372184D01*
X41453Y372253D01*
X41813Y372323D01*
X42132Y372406D01*
X42285Y372448D01*
X42424Y372489D01*
Y372503D01*
Y372531D01*
X42438Y372614D01*
Y372711D01*
Y372767D01*
Y372794D01*
Y372808D01*
Y372822D01*
Y372905D01*
X42424Y373044D01*
X42396Y373197D01*
X42354Y373363D01*
X42285Y373529D01*
X42202Y373682D01*
X42091Y373807D01*
X42077Y373821D01*
X42007Y373876D01*
X41897Y373932D01*
X41758Y374015D01*
X41564Y374084D01*
X41342Y374154D01*
X41065Y374195D01*
X40746Y374209D01*
X40607D01*
X40468Y374195D01*
X40274Y374167D01*
X40080Y374140D01*
X39872Y374084D01*
X39678Y374015D01*
X39511Y373918D01*
X39497Y373904D01*
X39442Y373862D01*
X39372Y373793D01*
X39289Y373682D01*
X39206Y373543D01*
X39109Y373363D01*
X39026Y373141D01*
X38943Y372892D01*
X37792Y373044D01*
Y373058D01*
X37805Y373072D01*
Y373113D01*
X37819Y373169D01*
X37861Y373294D01*
X37916Y373474D01*
X37986Y373654D01*
X38069Y373848D01*
X38180Y374043D01*
X38305Y374223D01*
X38319Y374237D01*
X38374Y374292D01*
X38457Y374375D01*
X38568Y374486D01*
X38721Y374597D01*
X38901Y374708D01*
X39109Y374833D01*
X39345Y374930D01*
X39359D01*
X39372Y374944D01*
X39414Y374958D01*
X39470Y374972D01*
X39608Y375013D01*
X39802Y375055D01*
X40024Y375097D01*
X40302Y375138D01*
X40593Y375166D01*
X40926Y375180D01*
X41078D01*
X41231Y375166D01*
D02*
G37*
G36*
X20525Y374223D02*
X20539Y374237D01*
X20567Y374264D01*
X20609Y374306D01*
X20678Y374375D01*
X20747Y374445D01*
X20844Y374528D01*
X20969Y374611D01*
X21094Y374708D01*
X21233Y374791D01*
X21385Y374875D01*
X21746Y375027D01*
X21940Y375097D01*
X22148Y375138D01*
X22370Y375166D01*
X22592Y375180D01*
X22717D01*
X22869Y375166D01*
X23049Y375138D01*
X23258Y375110D01*
X23479Y375055D01*
X23701Y374972D01*
X23923Y374875D01*
X23951Y374861D01*
X24020Y374819D01*
X24117Y374750D01*
X24242Y374653D01*
X24367Y374528D01*
X24506Y374389D01*
X24630Y374223D01*
X24741Y374029D01*
X24755Y374001D01*
X24783Y373932D01*
X24825Y373807D01*
X24866Y373627D01*
X24908Y373405D01*
X24949Y373141D01*
X24977Y372822D01*
X24991Y372462D01*
Y368065D01*
X23812D01*
Y372475D01*
Y372489D01*
Y372517D01*
Y372559D01*
Y372614D01*
X23798Y372767D01*
X23771Y372961D01*
X23715Y373169D01*
X23646Y373377D01*
X23549Y373585D01*
X23424Y373751D01*
X23410Y373765D01*
X23354Y373821D01*
X23271Y373890D01*
X23147Y373959D01*
X22994Y374043D01*
X22814Y374098D01*
X22592Y374154D01*
X22342Y374167D01*
X22259D01*
X22162Y374154D01*
X22023Y374140D01*
X21885Y374098D01*
X21718Y374056D01*
X21552Y373987D01*
X21371Y373890D01*
X21358Y373876D01*
X21302Y373834D01*
X21219Y373779D01*
X21122Y373696D01*
X21011Y373585D01*
X20900Y373460D01*
X20803Y373307D01*
X20719Y373141D01*
X20706Y373113D01*
X20692Y373058D01*
X20664Y372947D01*
X20622Y372808D01*
X20581Y372628D01*
X20553Y372406D01*
X20539Y372156D01*
X20525Y371865D01*
Y368065D01*
X19347D01*
Y377662D01*
X20525D01*
Y374223D01*
D02*
G37*
G36*
X18473Y368065D02*
X17031D01*
X15907Y370978D01*
X11885D01*
X10845Y368065D01*
X9500D01*
X13161Y377662D01*
X14548D01*
X18473Y368065D01*
D02*
G37*
G36*
X90270Y375166D02*
X90394Y375152D01*
X90533Y375124D01*
X90686Y375097D01*
X90866Y375069D01*
X91240Y374944D01*
X91434Y374875D01*
X91629Y374778D01*
X91823Y374680D01*
X92017Y374542D01*
X92197Y374403D01*
X92378Y374237D01*
X92391Y374223D01*
X92419Y374195D01*
X92461Y374140D01*
X92516Y374070D01*
X92586Y373973D01*
X92669Y373848D01*
X92752Y373710D01*
X92835Y373557D01*
X92918Y373391D01*
X93002Y373183D01*
X93085Y372975D01*
X93154Y372739D01*
X93210Y372489D01*
X93251Y372226D01*
X93279Y371949D01*
X93293Y371643D01*
Y371629D01*
Y371588D01*
Y371519D01*
Y371422D01*
X93279Y371311D01*
X93265Y371172D01*
Y371033D01*
X93237Y370881D01*
X93196Y370534D01*
X93113Y370187D01*
X93015Y369841D01*
X92877Y369521D01*
Y369508D01*
X92863Y369494D01*
X92835Y369452D01*
X92808Y369397D01*
X92710Y369258D01*
X92586Y369092D01*
X92419Y368897D01*
X92211Y368703D01*
X91975Y368509D01*
X91698Y368329D01*
X91684D01*
X91670Y368315D01*
X91629Y368287D01*
X91559Y368260D01*
X91490Y368232D01*
X91407Y368204D01*
X91199Y368121D01*
X90963Y368051D01*
X90672Y367982D01*
X90367Y367927D01*
X90034Y367913D01*
X89895D01*
X89784Y367927D01*
X89659Y367940D01*
X89521Y367968D01*
X89354Y367996D01*
X89188Y368024D01*
X88813Y368135D01*
X88605Y368218D01*
X88411Y368301D01*
X88217Y368412D01*
X88023Y368537D01*
X87843Y368675D01*
X87662Y368842D01*
X87648Y368856D01*
X87621Y368884D01*
X87579Y368939D01*
X87524Y369022D01*
X87454Y369119D01*
X87385Y369230D01*
X87302Y369369D01*
X87219Y369535D01*
X87135Y369716D01*
X87052Y369924D01*
X86983Y370146D01*
X86913Y370381D01*
X86858Y370645D01*
X86816Y370922D01*
X86789Y371227D01*
X86775Y371546D01*
Y371574D01*
Y371629D01*
X86789Y371727D01*
Y371865D01*
X86803Y372018D01*
X86830Y372212D01*
X86858Y372406D01*
X86913Y372628D01*
X86969Y372850D01*
X87038Y373086D01*
X87121Y373335D01*
X87232Y373571D01*
X87343Y373793D01*
X87496Y374015D01*
X87648Y374223D01*
X87843Y374403D01*
X87857Y374417D01*
X87884Y374431D01*
X87940Y374473D01*
X88009Y374528D01*
X88092Y374584D01*
X88203Y374653D01*
X88314Y374722D01*
X88453Y374791D01*
X88605Y374861D01*
X88772Y374930D01*
X89146Y375055D01*
X89576Y375152D01*
X89798Y375166D01*
X90034Y375180D01*
X90173D01*
X90270Y375166D01*
D02*
G37*
G36*
X82517D02*
X82614Y375152D01*
X82739Y375124D01*
X82878Y375097D01*
X83030Y375055D01*
X83183Y375000D01*
X83349Y374930D01*
X83516Y374847D01*
X83696Y374750D01*
X83862Y374639D01*
X84029Y374500D01*
X84195Y374348D01*
X84348Y374167D01*
Y375027D01*
X85429D01*
Y369008D01*
Y368994D01*
Y368939D01*
Y368856D01*
Y368745D01*
X85416Y368620D01*
Y368467D01*
X85402Y368301D01*
X85388Y368121D01*
X85346Y367746D01*
X85291Y367358D01*
X85249Y367178D01*
X85208Y367011D01*
X85152Y366859D01*
X85097Y366720D01*
Y366706D01*
X85083Y366692D01*
X85027Y366609D01*
X84958Y366484D01*
X84847Y366332D01*
X84694Y366165D01*
X84514Y365985D01*
X84292Y365805D01*
X84043Y365652D01*
X84029D01*
X84015Y365638D01*
X83973Y365611D01*
X83918Y365597D01*
X83848Y365555D01*
X83765Y365527D01*
X83557Y365458D01*
X83308Y365375D01*
X83003Y365319D01*
X82656Y365264D01*
X82281Y365250D01*
X82157D01*
X82073Y365264D01*
X81962D01*
X81851Y365278D01*
X81713Y365292D01*
X81560Y365319D01*
X81241Y365389D01*
X80908Y365486D01*
X80576Y365624D01*
X80271Y365819D01*
X80257Y365832D01*
X80243Y365846D01*
X80146Y365929D01*
X80035Y366054D01*
X79896Y366235D01*
X79757Y366470D01*
X79633Y366762D01*
X79591Y366928D01*
X79563Y367108D01*
X79535Y367289D01*
Y367497D01*
X80687Y367344D01*
Y367316D01*
X80700Y367261D01*
X80728Y367164D01*
X80756Y367039D01*
X80811Y366914D01*
X80881Y366789D01*
X80964Y366665D01*
X81075Y366567D01*
X81103Y366554D01*
X81158Y366512D01*
X81255Y366456D01*
X81394Y366401D01*
X81560Y366332D01*
X81768Y366276D01*
X82018Y366235D01*
X82281Y366221D01*
X82420D01*
X82559Y366235D01*
X82753Y366262D01*
X82947Y366304D01*
X83155Y366359D01*
X83363Y366443D01*
X83543Y366554D01*
X83557Y366567D01*
X83613Y366609D01*
X83696Y366692D01*
X83793Y366789D01*
X83890Y366928D01*
X83987Y367081D01*
X84084Y367261D01*
X84154Y367469D01*
Y367483D01*
X84167Y367538D01*
X84181Y367649D01*
X84195Y367788D01*
X84209Y367885D01*
Y367996D01*
X84223Y368121D01*
Y368260D01*
Y368412D01*
X84237Y368592D01*
Y368773D01*
Y368981D01*
X84223Y368967D01*
X84195Y368939D01*
X84154Y368897D01*
X84098Y368842D01*
X84029Y368773D01*
X83932Y368689D01*
X83821Y368606D01*
X83710Y368523D01*
X83419Y368357D01*
X83100Y368204D01*
X82919Y368148D01*
X82725Y368107D01*
X82517Y368079D01*
X82309Y368065D01*
X82240D01*
X82170Y368079D01*
X82073Y368079D01*
X81948Y368093D01*
X81810Y368121D01*
X81657Y368148D01*
X81491Y368190D01*
X81311Y368246D01*
X81130Y368315D01*
X80950Y368398D01*
X80756Y368495D01*
X80576Y368620D01*
X80395Y368759D01*
X80229Y368911D01*
X80076Y369091D01*
X80062Y369105D01*
X80049Y369133D01*
X80007Y369202D01*
X79952Y369272D01*
X79896Y369383D01*
X79827Y369494D01*
X79757Y369632D01*
X79688Y369799D01*
X79619Y369965D01*
X79549Y370159D01*
X79480Y370354D01*
X79425Y370575D01*
X79327Y371047D01*
X79314Y371311D01*
X79300Y371574D01*
Y371588D01*
Y371616D01*
Y371671D01*
Y371740D01*
X79314Y371838D01*
Y371935D01*
X79341Y372184D01*
X79383Y372462D01*
X79452Y372767D01*
X79535Y373086D01*
X79660Y373405D01*
Y373419D01*
X79674Y373446D01*
X79702Y373488D01*
X79730Y373543D01*
X79813Y373696D01*
X79924Y373890D01*
X80076Y374098D01*
X80257Y374306D01*
X80465Y374528D01*
X80700Y374708D01*
X80714D01*
X80728Y374722D01*
X80770Y374750D01*
X80825Y374778D01*
X80964Y374861D01*
X81158Y374944D01*
X81394Y375027D01*
X81671Y375110D01*
X81976Y375166D01*
X82309Y375180D01*
X82434D01*
X82517Y375166D01*
D02*
G37*
G36*
X26333Y407918D02*
X25155D01*
Y409263D01*
X26333D01*
Y407918D01*
D02*
G37*
G36*
X50520Y409416D02*
X50617D01*
X50880Y409388D01*
X51172Y409347D01*
X51477Y409277D01*
X51810Y409194D01*
X52115Y409083D01*
X52129D01*
X52156Y409069D01*
X52198Y409041D01*
X52253Y409014D01*
X52392Y408944D01*
X52572Y408820D01*
X52780Y408681D01*
X52988Y408501D01*
X53183Y408293D01*
X53363Y408057D01*
Y408043D01*
X53377Y408029D01*
X53404Y407987D01*
X53432Y407946D01*
X53502Y407807D01*
X53585Y407627D01*
X53682Y407405D01*
X53751Y407141D01*
X53821Y406864D01*
X53848Y406559D01*
X52628Y406462D01*
Y406476D01*
Y406503D01*
X52614Y406545D01*
X52600Y406614D01*
X52558Y406767D01*
X52503Y406975D01*
X52420Y407197D01*
X52295Y407419D01*
X52142Y407627D01*
X51948Y407821D01*
X51920Y407835D01*
X51851Y407890D01*
X51712Y407974D01*
X51532Y408057D01*
X51296Y408140D01*
X51019Y408223D01*
X50672Y408279D01*
X50284Y408293D01*
X50090D01*
X50007Y408279D01*
X49896Y408265D01*
X49646Y408237D01*
X49369Y408182D01*
X49091Y408112D01*
X48828Y408001D01*
X48717Y407932D01*
X48606Y407863D01*
X48578Y407849D01*
X48523Y407793D01*
X48439Y407696D01*
X48356Y407585D01*
X48259Y407433D01*
X48176Y407266D01*
X48121Y407072D01*
X48093Y406850D01*
Y406823D01*
Y406767D01*
X48107Y406670D01*
X48134Y406559D01*
X48176Y406420D01*
X48245Y406282D01*
X48329Y406143D01*
X48453Y406004D01*
X48467Y405990D01*
X48537Y405949D01*
X48592Y405907D01*
X48648Y405880D01*
X48731Y405838D01*
X48828Y405782D01*
X48953Y405741D01*
X49091Y405685D01*
X49244Y405630D01*
X49424Y405560D01*
X49618Y405505D01*
X49840Y405436D01*
X50090Y405380D01*
X50367Y405311D01*
X50381D01*
X50437Y405297D01*
X50520Y405283D01*
X50617Y405255D01*
X50742Y405228D01*
X50894Y405186D01*
X51047Y405144D01*
X51213Y405103D01*
X51574Y405006D01*
X51920Y404909D01*
X52087Y404853D01*
X52239Y404798D01*
X52378Y404756D01*
X52489Y404701D01*
X52503D01*
X52531Y404687D01*
X52572Y404659D01*
X52628Y404631D01*
X52780Y404548D01*
X52961Y404437D01*
X53169Y404285D01*
X53377Y404118D01*
X53571Y403924D01*
X53737Y403716D01*
X53751Y403688D01*
X53807Y403619D01*
X53862Y403494D01*
X53945Y403328D01*
X54015Y403134D01*
X54084Y402898D01*
X54126Y402634D01*
X54139Y402357D01*
Y402343D01*
Y402329D01*
Y402287D01*
Y402232D01*
X54112Y402080D01*
X54084Y401885D01*
X54029Y401664D01*
X53959Y401428D01*
X53848Y401178D01*
X53696Y400915D01*
Y400901D01*
X53682Y400887D01*
X53612Y400804D01*
X53515Y400679D01*
X53377Y400540D01*
X53196Y400374D01*
X52975Y400193D01*
X52725Y400027D01*
X52434Y399874D01*
X52420D01*
X52392Y399861D01*
X52350Y399847D01*
X52295Y399819D01*
X52212Y399791D01*
X52115Y399750D01*
X51893Y399694D01*
X51629Y399625D01*
X51310Y399556D01*
X50964Y399514D01*
X50589Y399500D01*
X50367D01*
X50256Y399514D01*
X50132D01*
X49993Y399528D01*
X49826Y399542D01*
X49480Y399597D01*
X49119Y399652D01*
X48759Y399750D01*
X48412Y399874D01*
X48398D01*
X48370Y399888D01*
X48329Y399916D01*
X48273Y399944D01*
X48107Y400027D01*
X47913Y400152D01*
X47691Y400318D01*
X47455Y400512D01*
X47233Y400748D01*
X47025Y401012D01*
Y401026D01*
X46997Y401053D01*
X46983Y401095D01*
X46942Y401150D01*
X46914Y401220D01*
X46872Y401303D01*
X46775Y401511D01*
X46678Y401774D01*
X46595Y402066D01*
X46540Y402398D01*
X46512Y402745D01*
X47705Y402856D01*
Y402842D01*
Y402828D01*
X47718Y402787D01*
Y402731D01*
X47746Y402607D01*
X47788Y402426D01*
X47843Y402246D01*
X47899Y402038D01*
X47996Y401844D01*
X48093Y401664D01*
X48107Y401650D01*
X48148Y401594D01*
X48218Y401497D01*
X48329Y401400D01*
X48467Y401275D01*
X48620Y401150D01*
X48828Y401026D01*
X49050Y400915D01*
X49064D01*
X49078Y400901D01*
X49119Y400887D01*
X49161Y400873D01*
X49299Y400831D01*
X49480Y400776D01*
X49702Y400720D01*
X49951Y400679D01*
X50229Y400651D01*
X50534Y400637D01*
X50658D01*
X50797Y400651D01*
X50964Y400665D01*
X51158Y400693D01*
X51380Y400720D01*
X51602Y400776D01*
X51810Y400845D01*
X51837Y400859D01*
X51907Y400887D01*
X52004Y400942D01*
X52129Y400998D01*
X52253Y401095D01*
X52392Y401192D01*
X52531Y401303D01*
X52642Y401442D01*
X52656Y401455D01*
X52683Y401511D01*
X52725Y401580D01*
X52780Y401691D01*
X52836Y401802D01*
X52877Y401941D01*
X52905Y402093D01*
X52919Y402260D01*
Y402274D01*
Y402343D01*
X52905Y402426D01*
X52891Y402537D01*
X52850Y402648D01*
X52808Y402787D01*
X52739Y402925D01*
X52642Y403050D01*
X52628Y403064D01*
X52586Y403106D01*
X52531Y403161D01*
X52434Y403245D01*
X52323Y403328D01*
X52170Y403425D01*
X51990Y403522D01*
X51782Y403605D01*
X51768Y403619D01*
X51699Y403633D01*
X51588Y403674D01*
X51518Y403688D01*
X51421Y403716D01*
X51324Y403758D01*
X51199Y403785D01*
X51061Y403827D01*
X50894Y403868D01*
X50728Y403910D01*
X50534Y403966D01*
X50312Y404021D01*
X50076Y404077D01*
X50062D01*
X50020Y404090D01*
X49951Y404104D01*
X49868Y404132D01*
X49757Y404160D01*
X49632Y404188D01*
X49355Y404271D01*
X49050Y404368D01*
X48731Y404465D01*
X48453Y404562D01*
X48329Y404617D01*
X48218Y404673D01*
X48204D01*
X48190Y404687D01*
X48107Y404742D01*
X47982Y404812D01*
X47843Y404922D01*
X47677Y405047D01*
X47510Y405200D01*
X47344Y405380D01*
X47205Y405574D01*
X47191Y405602D01*
X47150Y405671D01*
X47094Y405782D01*
X47039Y405921D01*
X46983Y406101D01*
X46928Y406309D01*
X46886Y406531D01*
X46872Y406767D01*
Y406781D01*
Y406795D01*
Y406836D01*
Y406892D01*
X46900Y407030D01*
X46928Y407211D01*
X46969Y407419D01*
X47039Y407655D01*
X47136Y407890D01*
X47275Y408126D01*
Y408140D01*
X47288Y408154D01*
X47358Y408237D01*
X47455Y408348D01*
X47580Y408487D01*
X47746Y408639D01*
X47954Y408806D01*
X48204Y408958D01*
X48481Y409097D01*
X48495D01*
X48523Y409111D01*
X48564Y409125D01*
X48620Y409152D01*
X48689Y409180D01*
X48786Y409208D01*
X48994Y409263D01*
X49258Y409319D01*
X49563Y409374D01*
X49882Y409416D01*
X50242Y409430D01*
X50423D01*
X50520Y409416D01*
D02*
G37*
G36*
X39078Y406767D02*
X39231Y406753D01*
X39411Y406725D01*
X39605Y406684D01*
X39813Y406628D01*
X40008Y406545D01*
X40035Y406531D01*
X40091Y406503D01*
X40188Y406462D01*
X40299Y406393D01*
X40437Y406309D01*
X40562Y406198D01*
X40687Y406087D01*
X40798Y405949D01*
X40812Y405935D01*
X40840Y405880D01*
X40881Y405810D01*
X40951Y405713D01*
X41006Y405574D01*
X41062Y405436D01*
X41131Y405269D01*
X41172Y405089D01*
Y405075D01*
X41186Y405020D01*
X41200Y404936D01*
X41214Y404826D01*
Y404659D01*
X41228Y404465D01*
X41242Y404229D01*
Y403938D01*
Y399666D01*
X40063D01*
Y403882D01*
Y403896D01*
Y403910D01*
Y404007D01*
Y404132D01*
X40049Y404285D01*
X40035Y404465D01*
X40008Y404645D01*
X39966Y404812D01*
X39924Y404964D01*
Y404978D01*
X39897Y405020D01*
X39855Y405089D01*
X39813Y405172D01*
X39744Y405255D01*
X39661Y405353D01*
X39550Y405449D01*
X39425Y405533D01*
X39411Y405547D01*
X39370Y405574D01*
X39286Y405602D01*
X39189Y405644D01*
X39078Y405685D01*
X38940Y405727D01*
X38773Y405741D01*
X38607Y405755D01*
X38537D01*
X38482Y405741D01*
X38343Y405727D01*
X38163Y405699D01*
X37969Y405630D01*
X37747Y405547D01*
X37525Y405436D01*
X37317Y405269D01*
X37289Y405242D01*
X37234Y405172D01*
X37192Y405117D01*
X37151Y405047D01*
X37095Y404964D01*
X37054Y404867D01*
X36998Y404756D01*
X36943Y404617D01*
X36901Y404465D01*
X36859Y404299D01*
X36832Y404118D01*
X36804Y403924D01*
X36776Y403688D01*
Y403452D01*
Y399666D01*
X35597D01*
Y406628D01*
X36651D01*
Y405630D01*
X36665Y405644D01*
X36693Y405685D01*
X36735Y405741D01*
X36790Y405810D01*
X36873Y405893D01*
X36970Y405990D01*
X37081Y406101D01*
X37220Y406212D01*
X37359Y406309D01*
X37525Y406420D01*
X37705Y406517D01*
X37899Y406601D01*
X38121Y406670D01*
X38343Y406725D01*
X38593Y406767D01*
X38856Y406781D01*
X38967D01*
X39078Y406767D01*
D02*
G37*
G36*
X88547Y406767D02*
X88644D01*
X88741Y406753D01*
X88977Y406712D01*
X89227Y406642D01*
X89490Y406531D01*
X89754Y406393D01*
X89975Y406199D01*
X90003Y406171D01*
X90059Y406087D01*
X90156Y405963D01*
X90197Y405866D01*
X90253Y405769D01*
X90308Y405644D01*
X90350Y405519D01*
X90405Y405380D01*
X90447Y405214D01*
X90475Y405047D01*
X90502Y404853D01*
X90530Y404659D01*
Y404437D01*
Y399666D01*
X89351D01*
Y404035D01*
Y404049D01*
Y404063D01*
Y404146D01*
Y404271D01*
X89337Y404423D01*
X89324Y404590D01*
X89310Y404756D01*
X89282Y404923D01*
X89240Y405047D01*
Y405061D01*
X89213Y405103D01*
X89185Y405158D01*
X89143Y405228D01*
X89088Y405311D01*
X89018Y405394D01*
X88935Y405477D01*
X88824Y405560D01*
X88810Y405574D01*
X88769Y405588D01*
X88713Y405616D01*
X88616Y405658D01*
X88519Y405699D01*
X88394Y405727D01*
X88270Y405741D01*
X88117Y405755D01*
X88048D01*
X87992Y405741D01*
X87853Y405727D01*
X87687Y405699D01*
X87493Y405630D01*
X87285Y405547D01*
X87077Y405422D01*
X86883Y405255D01*
X86869Y405228D01*
X86813Y405158D01*
X86730Y405047D01*
X86647Y404881D01*
X86550Y404659D01*
X86481Y404396D01*
X86425Y404077D01*
X86397Y403702D01*
Y399666D01*
X85218D01*
Y404174D01*
Y404188D01*
Y404215D01*
Y404243D01*
Y404299D01*
X85205Y404451D01*
X85177Y404618D01*
X85149Y404812D01*
X85094Y405006D01*
X85024Y405186D01*
X84927Y405353D01*
X84913Y405366D01*
X84872Y405422D01*
X84803Y405477D01*
X84705Y405560D01*
X84581Y405630D01*
X84414Y405699D01*
X84220Y405741D01*
X83984Y405755D01*
X83901D01*
X83804Y405741D01*
X83693Y405727D01*
X83554Y405685D01*
X83388Y405644D01*
X83235Y405574D01*
X83069Y405491D01*
X83055Y405477D01*
X83000Y405436D01*
X82930Y405380D01*
X82833Y405297D01*
X82736Y405186D01*
X82639Y405047D01*
X82542Y404895D01*
X82459Y404715D01*
X82445Y404687D01*
X82431Y404618D01*
X82403Y404506D01*
X82362Y404354D01*
X82320Y404146D01*
X82292Y403896D01*
X82278Y403605D01*
X82265Y403272D01*
Y399666D01*
X81086D01*
Y406628D01*
X82140D01*
Y405630D01*
X82154Y405658D01*
X82195Y405713D01*
X82278Y405810D01*
X82375Y405921D01*
X82500Y406060D01*
X82653Y406199D01*
X82819Y406337D01*
X83013Y406462D01*
X83041Y406476D01*
X83111Y406517D01*
X83222Y406559D01*
X83374Y406628D01*
X83554Y406684D01*
X83762Y406726D01*
X83998Y406767D01*
X84248Y406781D01*
X84373D01*
X84525Y406767D01*
X84691Y406739D01*
X84900Y406698D01*
X85108Y406642D01*
X85316Y406559D01*
X85510Y406448D01*
X85538Y406434D01*
X85593Y406393D01*
X85676Y406323D01*
X85787Y406212D01*
X85898Y406087D01*
X86023Y405935D01*
X86134Y405755D01*
X86217Y405547D01*
X86231Y405560D01*
X86259Y405602D01*
X86300Y405658D01*
X86370Y405741D01*
X86453Y405838D01*
X86550Y405935D01*
X86661Y406046D01*
X86799Y406171D01*
X86952Y406282D01*
X87105Y406393D01*
X87285Y406490D01*
X87479Y406587D01*
X87687Y406670D01*
X87909Y406726D01*
X88131Y406767D01*
X88380Y406781D01*
X88478D01*
X88547Y406767D01*
D02*
G37*
G36*
X102304D02*
X102512Y406753D01*
X102734Y406726D01*
X102970Y406670D01*
X103220Y406614D01*
X103455Y406531D01*
X103469D01*
X103483Y406517D01*
X103553Y406490D01*
X103664Y406434D01*
X103802Y406365D01*
X103955Y406268D01*
X104107Y406157D01*
X104246Y406032D01*
X104371Y405893D01*
X104385Y405880D01*
X104412Y405824D01*
X104468Y405727D01*
X104537Y405616D01*
X104607Y405450D01*
X104676Y405269D01*
X104731Y405061D01*
X104787Y404826D01*
X103636Y404673D01*
Y404701D01*
X103622Y404756D01*
X103594Y404853D01*
X103553Y404978D01*
X103483Y405103D01*
X103400Y405242D01*
X103303Y405380D01*
X103164Y405505D01*
X103150Y405519D01*
X103095Y405547D01*
X103012Y405602D01*
X102887Y405658D01*
X102748Y405713D01*
X102568Y405769D01*
X102346Y405796D01*
X102110Y405810D01*
X101972D01*
X101833Y405796D01*
X101653Y405782D01*
X101472Y405741D01*
X101278Y405699D01*
X101098Y405630D01*
X100945Y405533D01*
X100931Y405519D01*
X100890Y405491D01*
X100834Y405436D01*
X100779Y405353D01*
X100709Y405269D01*
X100654Y405158D01*
X100612Y405033D01*
X100599Y404909D01*
Y404895D01*
Y404867D01*
X100612Y404826D01*
Y404770D01*
X100654Y404631D01*
X100737Y404493D01*
X100751Y404479D01*
X100765Y404465D01*
X100793Y404423D01*
X100848Y404382D01*
X100904Y404340D01*
X100987Y404285D01*
X101084Y404243D01*
X101195Y404188D01*
X101209D01*
X101236Y404174D01*
X101292Y404160D01*
X101389Y404118D01*
X101528Y404077D01*
X101708Y404035D01*
X101819Y403993D01*
X101944Y403966D01*
X102083Y403924D01*
X102235Y403882D01*
X102249D01*
X102290Y403869D01*
X102360Y403855D01*
X102443Y403827D01*
X102540Y403799D01*
X102665Y403772D01*
X102928Y403688D01*
X103220Y403605D01*
X103511Y403508D01*
X103774Y403411D01*
X103885Y403369D01*
X103982Y403328D01*
X104010Y403314D01*
X104066Y403286D01*
X104149Y403245D01*
X104274Y403175D01*
X104398Y403092D01*
X104523Y402981D01*
X104648Y402856D01*
X104759Y402718D01*
X104773Y402704D01*
X104801Y402648D01*
X104856Y402565D01*
X104912Y402440D01*
X104953Y402288D01*
X105009Y402121D01*
X105036Y401927D01*
X105050Y401705D01*
Y401677D01*
Y401608D01*
X105036Y401497D01*
X105009Y401344D01*
X104967Y401178D01*
X104898Y400998D01*
X104815Y400790D01*
X104704Y400596D01*
X104690Y400568D01*
X104634Y400512D01*
X104565Y400415D01*
X104454Y400304D01*
X104301Y400180D01*
X104135Y400041D01*
X103941Y399916D01*
X103705Y399791D01*
X103691D01*
X103677Y399777D01*
X103594Y399750D01*
X103455Y399708D01*
X103275Y399653D01*
X103053Y399597D01*
X102804Y399556D01*
X102540Y399528D01*
X102235Y399514D01*
X102110D01*
X102013Y399528D01*
X101902D01*
X101763Y399542D01*
X101625Y399556D01*
X101472Y399583D01*
X101139Y399653D01*
X100793Y399750D01*
X100460Y399888D01*
X100307Y399972D01*
X100169Y400069D01*
X100155Y400083D01*
X100141Y400096D01*
X100058Y400180D01*
X99933Y400304D01*
X99794Y400499D01*
X99642Y400734D01*
X99489Y401012D01*
X99364Y401358D01*
X99267Y401747D01*
X100432Y401927D01*
Y401913D01*
Y401899D01*
X100460Y401816D01*
X100488Y401677D01*
X100543Y401525D01*
X100612Y401358D01*
X100696Y401178D01*
X100821Y400998D01*
X100973Y400845D01*
X101001Y400831D01*
X101056Y400790D01*
X101167Y400734D01*
X101306Y400665D01*
X101486Y400596D01*
X101694Y400540D01*
X101944Y400499D01*
X102235Y400485D01*
X102374D01*
X102512Y400499D01*
X102693Y400526D01*
X102887Y400568D01*
X103095Y400623D01*
X103275Y400693D01*
X103442Y400804D01*
X103455Y400817D01*
X103511Y400859D01*
X103566Y400928D01*
X103650Y401026D01*
X103719Y401137D01*
X103788Y401275D01*
X103830Y401414D01*
X103844Y401580D01*
Y401594D01*
Y401650D01*
X103830Y401719D01*
X103802Y401816D01*
X103761Y401913D01*
X103691Y402010D01*
X103608Y402121D01*
X103483Y402204D01*
X103469Y402218D01*
X103428Y402232D01*
X103358Y402274D01*
X103247Y402315D01*
X103081Y402371D01*
X102984Y402412D01*
X102873Y402440D01*
X102748Y402482D01*
X102610Y402523D01*
X102457Y402565D01*
X102277Y402607D01*
X102263D01*
X102221Y402620D01*
X102152Y402634D01*
X102069Y402662D01*
X101958Y402690D01*
X101833Y402731D01*
X101569Y402801D01*
X101264Y402898D01*
X100973Y402981D01*
X100696Y403078D01*
X100571Y403134D01*
X100474Y403175D01*
X100446Y403189D01*
X100391Y403217D01*
X100307Y403272D01*
X100196Y403342D01*
X100072Y403439D01*
X99947Y403550D01*
X99822Y403674D01*
X99711Y403827D01*
X99697Y403841D01*
X99669Y403896D01*
X99628Y403993D01*
X99586Y404104D01*
X99545Y404243D01*
X99503Y404409D01*
X99475Y404576D01*
X99461Y404770D01*
Y404798D01*
Y404853D01*
X99475Y404936D01*
X99489Y405061D01*
X99517Y405186D01*
X99545Y405339D01*
X99600Y405477D01*
X99669Y405630D01*
X99683Y405644D01*
X99711Y405699D01*
X99753Y405769D01*
X99822Y405866D01*
X99905Y405963D01*
X100002Y406087D01*
X100113Y406199D01*
X100252Y406296D01*
X100266Y406309D01*
X100307Y406323D01*
X100363Y406365D01*
X100446Y406407D01*
X100557Y406462D01*
X100682Y406517D01*
X100834Y406573D01*
X101001Y406628D01*
X101028Y406642D01*
X101084Y406656D01*
X101181Y406684D01*
X101306Y406712D01*
X101458Y406739D01*
X101625Y406753D01*
X101819Y406781D01*
X102152D01*
X102304Y406767D01*
D02*
G37*
G36*
X71711Y402718D02*
Y402704D01*
Y402662D01*
Y402607D01*
Y402523D01*
X71697Y402412D01*
Y402301D01*
X71669Y402038D01*
X71641Y401733D01*
X71586Y401414D01*
X71503Y401123D01*
X71406Y400845D01*
Y400831D01*
X71392Y400817D01*
X71350Y400734D01*
X71281Y400623D01*
X71184Y400471D01*
X71045Y400318D01*
X70893Y400152D01*
X70698Y399985D01*
X70476Y399847D01*
X70449Y399833D01*
X70366Y399791D01*
X70241Y399736D01*
X70060Y399680D01*
X69839Y399611D01*
X69589Y399556D01*
X69311Y399514D01*
X69006Y399500D01*
X68882D01*
X68798Y399514D01*
X68687Y399528D01*
X68576Y399542D01*
X68285Y399597D01*
X67980Y399680D01*
X67661Y399805D01*
X67495Y399888D01*
X67342Y399985D01*
X67203Y400096D01*
X67065Y400221D01*
X67051Y400235D01*
X67037Y400249D01*
X67009Y400304D01*
X66968Y400360D01*
X66912Y400429D01*
X66857Y400526D01*
X66801Y400637D01*
X66732Y400762D01*
X66677Y400901D01*
X66621Y401067D01*
X66565Y401233D01*
X66510Y401428D01*
X66482Y401636D01*
X66441Y401871D01*
X66427Y402107D01*
Y402371D01*
X67578Y402537D01*
Y402523D01*
Y402496D01*
Y402440D01*
X67592Y402357D01*
X67606Y402274D01*
Y402177D01*
X67647Y401941D01*
X67689Y401691D01*
X67772Y401442D01*
X67855Y401220D01*
X67911Y401123D01*
X67980Y401039D01*
X67994Y401026D01*
X68049Y400984D01*
X68133Y400915D01*
X68244Y400845D01*
X68396Y400762D01*
X68563Y400706D01*
X68771Y400651D01*
X68993Y400637D01*
X69076D01*
X69159Y400651D01*
X69284Y400665D01*
X69408Y400693D01*
X69547Y400720D01*
X69686Y400776D01*
X69825Y400845D01*
X69839Y400859D01*
X69880Y400887D01*
X69935Y400942D01*
X70019Y400998D01*
X70088Y401095D01*
X70171Y401192D01*
X70241Y401303D01*
X70296Y401442D01*
Y401455D01*
X70324Y401511D01*
X70338Y401608D01*
X70366Y401733D01*
X70393Y401899D01*
X70407Y402107D01*
X70435Y402357D01*
Y402648D01*
Y409263D01*
X71711D01*
Y402718D01*
D02*
G37*
G36*
X12784D02*
Y402704D01*
Y402662D01*
Y402607D01*
Y402523D01*
X12770Y402412D01*
Y402301D01*
X12742Y402038D01*
X12715Y401733D01*
X12659Y401414D01*
X12576Y401123D01*
X12479Y400845D01*
Y400831D01*
X12465Y400817D01*
X12423Y400734D01*
X12354Y400623D01*
X12257Y400471D01*
X12118Y400318D01*
X11966Y400152D01*
X11772Y399985D01*
X11550Y399847D01*
X11522Y399833D01*
X11439Y399791D01*
X11314Y399736D01*
X11134Y399680D01*
X10912Y399611D01*
X10662Y399556D01*
X10385Y399514D01*
X10079Y399500D01*
X9955D01*
X9872Y399514D01*
X9761Y399528D01*
X9650Y399542D01*
X9358Y399597D01*
X9053Y399680D01*
X8734Y399805D01*
X8568Y399888D01*
X8415Y399985D01*
X8277Y400096D01*
X8138Y400221D01*
X8124Y400235D01*
X8110Y400249D01*
X8083Y400304D01*
X8041Y400360D01*
X7985Y400429D01*
X7930Y400526D01*
X7875Y400637D01*
X7805Y400762D01*
X7750Y400901D01*
X7694Y401067D01*
X7639Y401233D01*
X7583Y401428D01*
X7556Y401636D01*
X7514Y401871D01*
X7500Y402107D01*
Y402371D01*
X8651Y402537D01*
Y402523D01*
Y402496D01*
Y402440D01*
X8665Y402357D01*
X8679Y402274D01*
Y402177D01*
X8720Y401941D01*
X8762Y401691D01*
X8845Y401442D01*
X8928Y401220D01*
X8984Y401123D01*
X9053Y401039D01*
X9067Y401026D01*
X9123Y400984D01*
X9206Y400915D01*
X9317Y400845D01*
X9469Y400762D01*
X9636Y400706D01*
X9844Y400651D01*
X10066Y400637D01*
X10149D01*
X10232Y400651D01*
X10357Y400665D01*
X10482Y400693D01*
X10620Y400720D01*
X10759Y400776D01*
X10898Y400845D01*
X10912Y400859D01*
X10953Y400887D01*
X11009Y400942D01*
X11092Y400998D01*
X11161Y401095D01*
X11244Y401192D01*
X11314Y401303D01*
X11369Y401442D01*
Y401455D01*
X11397Y401511D01*
X11411Y401608D01*
X11439Y401733D01*
X11466Y401899D01*
X11480Y402107D01*
X11508Y402357D01*
Y402648D01*
Y409263D01*
X12784D01*
Y402718D01*
D02*
G37*
G36*
X20328Y399666D02*
X19274D01*
Y400679D01*
X19260Y400665D01*
X19233Y400623D01*
X19191Y400568D01*
X19122Y400499D01*
X19038Y400415D01*
X18941Y400304D01*
X18830Y400207D01*
X18692Y400096D01*
X18539Y399985D01*
X18373Y399888D01*
X18192Y399791D01*
X17998Y399694D01*
X17776Y399625D01*
X17555Y399569D01*
X17305Y399528D01*
X17055Y399514D01*
X16958D01*
X16833Y399528D01*
X16681Y399542D01*
X16501Y399569D01*
X16306Y399611D01*
X16112Y399666D01*
X15904Y399750D01*
X15876Y399763D01*
X15821Y399791D01*
X15724Y399847D01*
X15613Y399916D01*
X15474Y399999D01*
X15350Y400096D01*
X15225Y400207D01*
X15114Y400332D01*
X15100Y400346D01*
X15072Y400401D01*
X15031Y400471D01*
X14975Y400582D01*
X14906Y400706D01*
X14850Y400859D01*
X14795Y401026D01*
X14753Y401206D01*
Y401220D01*
X14739Y401275D01*
X14725Y401358D01*
Y401469D01*
X14712Y401636D01*
X14698Y401816D01*
X14684Y402052D01*
Y402315D01*
Y406628D01*
X15863D01*
Y402759D01*
Y402745D01*
Y402718D01*
Y402676D01*
Y402607D01*
Y402454D01*
X15876Y402260D01*
Y402052D01*
X15890Y401844D01*
X15904Y401664D01*
X15932Y401511D01*
Y401497D01*
X15960Y401442D01*
X15987Y401358D01*
X16029Y401247D01*
X16098Y401137D01*
X16182Y401012D01*
X16279Y400901D01*
X16403Y400790D01*
X16417Y400776D01*
X16473Y400748D01*
X16542Y400706D01*
X16653Y400665D01*
X16778Y400610D01*
X16931Y400568D01*
X17097Y400540D01*
X17291Y400526D01*
X17388D01*
X17485Y400540D01*
X17610Y400554D01*
X17763Y400596D01*
X17929Y400637D01*
X18109Y400706D01*
X18290Y400790D01*
X18317Y400804D01*
X18373Y400845D01*
X18456Y400901D01*
X18553Y400984D01*
X18664Y401095D01*
X18775Y401220D01*
X18872Y401358D01*
X18955Y401525D01*
X18969Y401553D01*
X18983Y401608D01*
X19011Y401719D01*
X19052Y401871D01*
X19094Y402066D01*
X19122Y402301D01*
X19136Y402579D01*
X19150Y402898D01*
Y406628D01*
X20328D01*
Y399666D01*
D02*
G37*
G36*
X76884Y406767D02*
X77092Y406753D01*
X77327Y406725D01*
X77563Y406684D01*
X77799Y406628D01*
X78021Y406559D01*
X78049Y406545D01*
X78118Y406517D01*
X78215Y406476D01*
X78340Y406420D01*
X78478Y406337D01*
X78617Y406254D01*
X78742Y406143D01*
X78853Y406032D01*
X78867Y406018D01*
X78895Y405976D01*
X78936Y405907D01*
X78992Y405824D01*
X79061Y405699D01*
X79116Y405574D01*
X79172Y405422D01*
X79214Y405242D01*
Y405228D01*
X79227Y405186D01*
X79241Y405103D01*
X79255Y404992D01*
Y404839D01*
X79269Y404659D01*
X79283Y404423D01*
Y404160D01*
Y402579D01*
Y402565D01*
Y402509D01*
Y402426D01*
Y402315D01*
Y402191D01*
Y402038D01*
X79297Y401705D01*
Y401358D01*
X79311Y401012D01*
X79324Y400859D01*
Y400720D01*
X79338Y400596D01*
X79352Y400499D01*
Y400485D01*
X79366Y400429D01*
X79380Y400346D01*
X79422Y400235D01*
X79449Y400110D01*
X79505Y399972D01*
X79574Y399819D01*
X79643Y399666D01*
X78409D01*
X78395Y399680D01*
X78381Y399736D01*
X78354Y399805D01*
X78312Y399916D01*
X78271Y400041D01*
X78243Y400193D01*
X78215Y400360D01*
X78187Y400540D01*
X78173D01*
X78159Y400512D01*
X78076Y400443D01*
X77951Y400346D01*
X77785Y400221D01*
X77577Y400096D01*
X77369Y399958D01*
X77147Y399833D01*
X76911Y399736D01*
X76884Y399722D01*
X76800Y399708D01*
X76676Y399666D01*
X76523Y399625D01*
X76329Y399583D01*
X76107Y399556D01*
X75857Y399528D01*
X75608Y399514D01*
X75497D01*
X75414Y399528D01*
X75317D01*
X75205Y399542D01*
X74956Y399583D01*
X74679Y399652D01*
X74373Y399750D01*
X74096Y399888D01*
X73846Y400069D01*
X73819Y400096D01*
X73749Y400166D01*
X73652Y400290D01*
X73541Y400457D01*
X73430Y400665D01*
X73333Y400901D01*
X73264Y401192D01*
X73250Y401331D01*
X73236Y401497D01*
Y401525D01*
Y401580D01*
X73250Y401677D01*
X73264Y401802D01*
X73292Y401955D01*
X73333Y402107D01*
X73389Y402274D01*
X73458Y402426D01*
X73472Y402440D01*
X73500Y402496D01*
X73555Y402579D01*
X73625Y402676D01*
X73708Y402787D01*
X73819Y402898D01*
X73930Y403009D01*
X74068Y403106D01*
X74082Y403120D01*
X74138Y403147D01*
X74207Y403203D01*
X74318Y403258D01*
X74443Y403314D01*
X74595Y403383D01*
X74748Y403439D01*
X74928Y403494D01*
X74942D01*
X74998Y403508D01*
X75081Y403536D01*
X75192Y403550D01*
X75330Y403577D01*
X75511Y403605D01*
X75719Y403647D01*
X75968Y403674D01*
X75982D01*
X76038Y403688D01*
X76107D01*
X76204Y403702D01*
X76315Y403716D01*
X76454Y403744D01*
X76606Y403758D01*
X76773Y403785D01*
X77105Y403855D01*
X77466Y403924D01*
X77785Y404007D01*
X77938Y404049D01*
X78076Y404090D01*
Y404104D01*
Y404132D01*
X78090Y404215D01*
Y404312D01*
Y404368D01*
Y404395D01*
Y404409D01*
Y404423D01*
Y404506D01*
X78076Y404645D01*
X78049Y404798D01*
X78007Y404964D01*
X77938Y405131D01*
X77854Y405283D01*
X77744Y405408D01*
X77730Y405422D01*
X77660Y405477D01*
X77549Y405533D01*
X77411Y405616D01*
X77217Y405685D01*
X76995Y405755D01*
X76717Y405796D01*
X76398Y405810D01*
X76259D01*
X76121Y405796D01*
X75927Y405769D01*
X75732Y405741D01*
X75525Y405685D01*
X75330Y405616D01*
X75164Y405519D01*
X75150Y405505D01*
X75095Y405463D01*
X75025Y405394D01*
X74942Y405283D01*
X74859Y405144D01*
X74762Y404964D01*
X74679Y404742D01*
X74595Y404493D01*
X73444Y404645D01*
Y404659D01*
X73458Y404673D01*
Y404715D01*
X73472Y404770D01*
X73514Y404895D01*
X73569Y405075D01*
X73638Y405255D01*
X73722Y405449D01*
X73833Y405644D01*
X73957Y405824D01*
X73971Y405838D01*
X74027Y405893D01*
X74110Y405976D01*
X74221Y406087D01*
X74373Y406198D01*
X74554Y406309D01*
X74762Y406434D01*
X74998Y406531D01*
X75011D01*
X75025Y406545D01*
X75067Y406559D01*
X75122Y406573D01*
X75261Y406614D01*
X75455Y406656D01*
X75677Y406698D01*
X75954Y406739D01*
X76246Y406767D01*
X76578Y406781D01*
X76731D01*
X76884Y406767D01*
D02*
G37*
G36*
X61143Y399666D02*
X59798D01*
Y401012D01*
X61143D01*
Y399666D01*
D02*
G37*
G36*
X31381Y406767D02*
X31589Y406753D01*
X31825Y406725D01*
X32061Y406684D01*
X32297Y406628D01*
X32519Y406559D01*
X32546Y406545D01*
X32616Y406517D01*
X32713Y406476D01*
X32838Y406420D01*
X32976Y406337D01*
X33115Y406254D01*
X33240Y406143D01*
X33351Y406032D01*
X33365Y406018D01*
X33392Y405976D01*
X33434Y405907D01*
X33489Y405824D01*
X33559Y405699D01*
X33614Y405574D01*
X33670Y405422D01*
X33711Y405242D01*
Y405228D01*
X33725Y405186D01*
X33739Y405103D01*
X33753Y404992D01*
Y404839D01*
X33767Y404659D01*
X33781Y404423D01*
Y404160D01*
Y402579D01*
Y402565D01*
Y402509D01*
Y402426D01*
Y402315D01*
Y402191D01*
Y402038D01*
X33795Y401705D01*
Y401358D01*
X33808Y401012D01*
X33822Y400859D01*
Y400720D01*
X33836Y400596D01*
X33850Y400499D01*
Y400485D01*
X33864Y400429D01*
X33878Y400346D01*
X33919Y400235D01*
X33947Y400110D01*
X34002Y399972D01*
X34072Y399819D01*
X34141Y399666D01*
X32907D01*
X32893Y399680D01*
X32879Y399736D01*
X32851Y399805D01*
X32810Y399916D01*
X32768Y400041D01*
X32740Y400193D01*
X32713Y400360D01*
X32685Y400540D01*
X32671D01*
X32657Y400512D01*
X32574Y400443D01*
X32449Y400346D01*
X32283Y400221D01*
X32075Y400096D01*
X31867Y399958D01*
X31645Y399833D01*
X31409Y399736D01*
X31381Y399722D01*
X31298Y399708D01*
X31173Y399666D01*
X31021Y399625D01*
X30827Y399583D01*
X30605Y399556D01*
X30355Y399528D01*
X30106Y399514D01*
X29995D01*
X29911Y399528D01*
X29814D01*
X29703Y399542D01*
X29454Y399583D01*
X29176Y399652D01*
X28871Y399750D01*
X28594Y399888D01*
X28344Y400069D01*
X28317Y400096D01*
X28247Y400166D01*
X28150Y400290D01*
X28039Y400457D01*
X27928Y400665D01*
X27831Y400901D01*
X27762Y401192D01*
X27748Y401331D01*
X27734Y401497D01*
Y401525D01*
Y401580D01*
X27748Y401677D01*
X27762Y401802D01*
X27789Y401955D01*
X27831Y402107D01*
X27887Y402274D01*
X27956Y402426D01*
X27970Y402440D01*
X27998Y402496D01*
X28053Y402579D01*
X28122Y402676D01*
X28205Y402787D01*
X28317Y402898D01*
X28427Y403009D01*
X28566Y403106D01*
X28580Y403120D01*
X28635Y403147D01*
X28705Y403203D01*
X28816Y403258D01*
X28941Y403314D01*
X29093Y403383D01*
X29246Y403439D01*
X29426Y403494D01*
X29440D01*
X29495Y403508D01*
X29578Y403536D01*
X29690Y403550D01*
X29828Y403577D01*
X30008Y403605D01*
X30216Y403647D01*
X30466Y403674D01*
X30480D01*
X30535Y403688D01*
X30605D01*
X30702Y403702D01*
X30813Y403716D01*
X30951Y403744D01*
X31104Y403758D01*
X31270Y403785D01*
X31603Y403855D01*
X31964Y403924D01*
X32283Y404007D01*
X32435Y404049D01*
X32574Y404090D01*
Y404104D01*
Y404132D01*
X32588Y404215D01*
Y404312D01*
Y404368D01*
Y404395D01*
Y404409D01*
Y404423D01*
Y404506D01*
X32574Y404645D01*
X32546Y404798D01*
X32505Y404964D01*
X32435Y405131D01*
X32352Y405283D01*
X32241Y405408D01*
X32227Y405422D01*
X32158Y405477D01*
X32047Y405533D01*
X31908Y405616D01*
X31714Y405685D01*
X31492Y405755D01*
X31215Y405796D01*
X30896Y405810D01*
X30757D01*
X30619Y405796D01*
X30424Y405769D01*
X30230Y405741D01*
X30022Y405685D01*
X29828Y405616D01*
X29662Y405519D01*
X29648Y405505D01*
X29592Y405463D01*
X29523Y405394D01*
X29440Y405283D01*
X29357Y405144D01*
X29260Y404964D01*
X29176Y404742D01*
X29093Y404493D01*
X27942Y404645D01*
Y404659D01*
X27956Y404673D01*
Y404715D01*
X27970Y404770D01*
X28011Y404895D01*
X28067Y405075D01*
X28136Y405255D01*
X28219Y405449D01*
X28330Y405644D01*
X28455Y405824D01*
X28469Y405838D01*
X28524Y405893D01*
X28608Y405976D01*
X28719Y406087D01*
X28871Y406198D01*
X29051Y406309D01*
X29260Y406434D01*
X29495Y406531D01*
X29509D01*
X29523Y406545D01*
X29565Y406559D01*
X29620Y406573D01*
X29759Y406614D01*
X29953Y406656D01*
X30175Y406698D01*
X30452Y406739D01*
X30743Y406767D01*
X31076Y406781D01*
X31229D01*
X31381Y406767D01*
D02*
G37*
G36*
X26333Y399666D02*
X25155D01*
Y406628D01*
X26333D01*
Y399666D01*
D02*
G37*
G36*
X23324D02*
X22145D01*
Y409263D01*
X23324D01*
Y399666D01*
D02*
G37*
G36*
X57107Y406628D02*
X58300D01*
Y405713D01*
X57107D01*
Y401622D01*
Y401594D01*
Y401539D01*
Y401455D01*
X57121Y401358D01*
X57135Y401137D01*
X57149Y401039D01*
X57163Y400970D01*
X57177Y400942D01*
X57218Y400887D01*
X57274Y400817D01*
X57371Y400748D01*
X57399Y400734D01*
X57468Y400706D01*
X57593Y400679D01*
X57773Y400665D01*
X57912D01*
X57981Y400679D01*
X58078D01*
X58189Y400693D01*
X58300Y400706D01*
X58453Y399666D01*
X58425D01*
X58369Y399652D01*
X58272Y399639D01*
X58147Y399625D01*
X58009Y399597D01*
X57856Y399583D01*
X57551Y399569D01*
X57440D01*
X57329Y399583D01*
X57190Y399597D01*
X57024Y399611D01*
X56858Y399652D01*
X56705Y399694D01*
X56553Y399763D01*
X56539Y399777D01*
X56497Y399805D01*
X56442Y399847D01*
X56358Y399916D01*
X56289Y399985D01*
X56206Y400083D01*
X56123Y400179D01*
X56067Y400304D01*
Y400318D01*
X56039Y400374D01*
X56026Y400471D01*
X55998Y400610D01*
X55970Y400790D01*
X55956Y400901D01*
Y401026D01*
X55942Y401178D01*
X55929Y401331D01*
Y401497D01*
Y401691D01*
Y405713D01*
X55055D01*
Y406628D01*
X55929D01*
Y408348D01*
X57107Y409055D01*
Y406628D01*
D02*
G37*
G36*
X95356Y406767D02*
X95467Y406753D01*
X95606Y406726D01*
X95758Y406698D01*
X95939Y406656D01*
X96105Y406614D01*
X96299Y406545D01*
X96480Y406476D01*
X96674Y406379D01*
X96868Y406268D01*
X97062Y406143D01*
X97242Y405990D01*
X97409Y405824D01*
X97423Y405810D01*
X97451Y405782D01*
X97492Y405727D01*
X97548Y405644D01*
X97617Y405547D01*
X97686Y405436D01*
X97769Y405297D01*
X97853Y405131D01*
X97936Y404950D01*
X98019Y404756D01*
X98088Y404534D01*
X98158Y404299D01*
X98213Y404035D01*
X98255Y403758D01*
X98283Y403466D01*
X98296Y403147D01*
Y403134D01*
Y403078D01*
Y402981D01*
X98283Y402842D01*
X93082D01*
Y402828D01*
Y402787D01*
X93096Y402731D01*
Y402648D01*
X93110Y402551D01*
X93137Y402440D01*
X93179Y402191D01*
X93262Y401913D01*
X93373Y401608D01*
X93526Y401331D01*
X93720Y401081D01*
X93734D01*
X93748Y401053D01*
X93831Y400984D01*
X93956Y400887D01*
X94122Y400790D01*
X94344Y400679D01*
X94594Y400582D01*
X94871Y400512D01*
X95023Y400499D01*
X95190Y400485D01*
X95301D01*
X95426Y400499D01*
X95578Y400526D01*
X95745Y400568D01*
X95939Y400623D01*
X96119Y400707D01*
X96299Y400817D01*
X96313Y400831D01*
X96383Y400887D01*
X96466Y400970D01*
X96563Y401081D01*
X96674Y401234D01*
X96799Y401428D01*
X96924Y401650D01*
X97034Y401913D01*
X98255Y401761D01*
Y401747D01*
X98241Y401719D01*
X98227Y401664D01*
X98199Y401580D01*
X98158Y401497D01*
X98116Y401386D01*
X98005Y401150D01*
X97866Y400887D01*
X97672Y400610D01*
X97451Y400346D01*
X97173Y400096D01*
X97159D01*
X97132Y400069D01*
X97090Y400041D01*
X97034Y399999D01*
X96951Y399958D01*
X96868Y399916D01*
X96757Y399861D01*
X96632Y399805D01*
X96494Y399750D01*
X96355Y399694D01*
X96008Y399611D01*
X95620Y399542D01*
X95190Y399514D01*
X95037D01*
X94940Y399528D01*
X94816Y399542D01*
X94663Y399569D01*
X94496Y399597D01*
X94316Y399625D01*
X93928Y399736D01*
X93720Y399819D01*
X93526Y399902D01*
X93318Y400013D01*
X93124Y400138D01*
X92943Y400277D01*
X92763Y400443D01*
X92749Y400457D01*
X92721Y400485D01*
X92680Y400540D01*
X92624Y400623D01*
X92555Y400720D01*
X92486Y400831D01*
X92402Y400970D01*
X92319Y401123D01*
X92236Y401303D01*
X92153Y401497D01*
X92083Y401719D01*
X92014Y401955D01*
X91959Y402204D01*
X91917Y402482D01*
X91889Y402773D01*
X91875Y403078D01*
Y403092D01*
Y403161D01*
Y403245D01*
X91889Y403369D01*
X91903Y403522D01*
X91917Y403688D01*
X91945Y403882D01*
X91986Y404077D01*
X92097Y404520D01*
X92167Y404742D01*
X92250Y404978D01*
X92361Y405200D01*
X92486Y405408D01*
X92624Y405616D01*
X92777Y405810D01*
X92791Y405824D01*
X92818Y405852D01*
X92874Y405893D01*
X92943Y405963D01*
X93026Y406032D01*
X93137Y406115D01*
X93262Y406212D01*
X93415Y406296D01*
X93567Y406393D01*
X93748Y406476D01*
X93942Y406559D01*
X94150Y406628D01*
X94372Y406698D01*
X94607Y406739D01*
X94857Y406767D01*
X95121Y406781D01*
X95259D01*
X95356Y406767D01*
D02*
G37*
G36*
X438282Y433087D02*
X438393Y433074D01*
X438517Y433046D01*
X438656Y433018D01*
X438809Y432990D01*
X439142Y432879D01*
X439322Y432796D01*
X439488Y432713D01*
X439669Y432602D01*
X439849Y432477D01*
X440029Y432338D01*
X440196Y432172D01*
X440209Y432158D01*
X440237Y432130D01*
X440279Y432075D01*
X440334Y432006D01*
X440404Y431922D01*
X440473Y431811D01*
X440556Y431687D01*
X440625Y431534D01*
X440709Y431381D01*
X440792Y431201D01*
X440861Y431021D01*
X440931Y430813D01*
X440986Y430591D01*
X441028Y430355D01*
X441055Y430120D01*
X441069Y429856D01*
Y429731D01*
X441055Y429648D01*
X441041Y429537D01*
X441028Y429412D01*
X441000Y429273D01*
X440972Y429121D01*
X440889Y428788D01*
X440750Y428441D01*
X440667Y428261D01*
X440570Y428095D01*
X440445Y427928D01*
X440320Y427762D01*
X440307Y427748D01*
X440279Y427720D01*
X440237Y427679D01*
X440182Y427637D01*
X440112Y427568D01*
X440015Y427498D01*
X439918Y427415D01*
X439793Y427332D01*
X439655Y427249D01*
X439516Y427165D01*
X439183Y427013D01*
X438795Y426888D01*
X438587Y426847D01*
X438365Y426819D01*
X438212Y427998D01*
X438226D01*
X438254Y428012D01*
X438310Y428025D01*
X438379Y428039D01*
X438462Y428053D01*
X438559Y428081D01*
X438767Y428150D01*
X439017Y428247D01*
X439253Y428372D01*
X439474Y428511D01*
X439669Y428677D01*
X439682Y428705D01*
X439738Y428760D01*
X439807Y428871D01*
X439877Y429010D01*
X439960Y429176D01*
X440029Y429384D01*
X440085Y429620D01*
X440098Y429870D01*
Y429953D01*
X440085Y430009D01*
X440071Y430161D01*
X440029Y430355D01*
X439960Y430577D01*
X439863Y430813D01*
X439724Y431049D01*
X439530Y431271D01*
X439502Y431298D01*
X439419Y431368D01*
X439294Y431451D01*
X439128Y431562D01*
X438920Y431673D01*
X438684Y431756D01*
X438406Y431825D01*
X438101Y431853D01*
X438088D01*
X438060D01*
X438018D01*
X437963Y431839D01*
X437810Y431825D01*
X437630Y431784D01*
X437408Y431728D01*
X437186Y431631D01*
X436964Y431493D01*
X436756Y431312D01*
X436729Y431284D01*
X436673Y431215D01*
X436590Y431104D01*
X436493Y430952D01*
X436396Y430757D01*
X436312Y430522D01*
X436257Y430258D01*
X436229Y429967D01*
Y429842D01*
X436243Y429745D01*
X436257Y429620D01*
X436285Y429482D01*
X436312Y429315D01*
X436354Y429135D01*
X435314Y429273D01*
Y429343D01*
X435328Y429398D01*
Y429579D01*
X435300Y429731D01*
X435272Y429911D01*
X435231Y430120D01*
X435161Y430355D01*
X435064Y430577D01*
X434939Y430813D01*
Y430827D01*
X434926Y430841D01*
X434870Y430910D01*
X434773Y431007D01*
X434648Y431118D01*
X434468Y431229D01*
X434260Y431326D01*
X434024Y431395D01*
X433885Y431423D01*
X433733D01*
X433719D01*
X433705D01*
X433622D01*
X433511Y431395D01*
X433358Y431368D01*
X433192Y431312D01*
X433012Y431243D01*
X432831Y431132D01*
X432665Y430979D01*
X432651Y430965D01*
X432596Y430896D01*
X432526Y430799D01*
X432443Y430674D01*
X432374Y430508D01*
X432304Y430314D01*
X432249Y430092D01*
X432235Y429842D01*
Y429731D01*
X432263Y429606D01*
X432291Y429440D01*
X432346Y429260D01*
X432415Y429079D01*
X432526Y428885D01*
X432665Y428705D01*
X432679Y428691D01*
X432748Y428636D01*
X432845Y428552D01*
X432984Y428455D01*
X433164Y428358D01*
X433386Y428261D01*
X433650Y428178D01*
X433955Y428122D01*
X433747Y426944D01*
X433733D01*
X433691Y426958D01*
X433636Y426971D01*
X433553Y426985D01*
X433456Y427013D01*
X433345Y427055D01*
X433081Y427138D01*
X432776Y427276D01*
X432471Y427443D01*
X432180Y427651D01*
X431916Y427914D01*
X431902Y427928D01*
X431888Y427956D01*
X431861Y427998D01*
X431819Y428053D01*
X431764Y428122D01*
X431708Y428219D01*
X431653Y428317D01*
X431583Y428441D01*
X431472Y428719D01*
X431361Y429038D01*
X431292Y429412D01*
X431264Y429606D01*
Y429953D01*
X431278Y430106D01*
X431306Y430286D01*
X431348Y430508D01*
X431417Y430757D01*
X431500Y431007D01*
X431611Y431257D01*
Y431271D01*
X431625Y431284D01*
X431666Y431368D01*
X431750Y431493D01*
X431847Y431631D01*
X431986Y431798D01*
X432138Y431964D01*
X432318Y432130D01*
X432526Y432269D01*
X432554Y432283D01*
X432623Y432325D01*
X432748Y432380D01*
X432901Y432449D01*
X433081Y432519D01*
X433289Y432574D01*
X433525Y432616D01*
X433761Y432630D01*
X433788D01*
X433872D01*
X433983Y432616D01*
X434135Y432588D01*
X434315Y432547D01*
X434510Y432477D01*
X434704Y432394D01*
X434898Y432283D01*
X434926Y432269D01*
X434981Y432228D01*
X435078Y432144D01*
X435189Y432033D01*
X435314Y431895D01*
X435453Y431728D01*
X435577Y431534D01*
X435702Y431298D01*
Y431312D01*
X435716Y431340D01*
X435730Y431381D01*
X435744Y431437D01*
X435799Y431590D01*
X435882Y431784D01*
X435993Y432006D01*
X436132Y432228D01*
X436312Y432435D01*
X436520Y432630D01*
X436548Y432644D01*
X436631Y432699D01*
X436770Y432782D01*
X436950Y432865D01*
X437172Y432949D01*
X437436Y433032D01*
X437741Y433087D01*
X438074Y433101D01*
X438088D01*
X438129D01*
X438199D01*
X438282Y433087D01*
D02*
G37*
G36*
Y425626D02*
X438393Y425612D01*
X438517Y425584D01*
X438656Y425557D01*
X438809Y425529D01*
X439142Y425418D01*
X439322Y425335D01*
X439488Y425252D01*
X439669Y425141D01*
X439849Y425016D01*
X440029Y424877D01*
X440196Y424711D01*
X440209Y424697D01*
X440237Y424669D01*
X440279Y424614D01*
X440334Y424544D01*
X440404Y424461D01*
X440473Y424350D01*
X440556Y424225D01*
X440625Y424073D01*
X440709Y423920D01*
X440792Y423740D01*
X440861Y423560D01*
X440931Y423352D01*
X440986Y423130D01*
X441028Y422894D01*
X441055Y422658D01*
X441069Y422395D01*
Y422270D01*
X441055Y422187D01*
X441041Y422076D01*
X441028Y421951D01*
X441000Y421812D01*
X440972Y421660D01*
X440889Y421327D01*
X440750Y420980D01*
X440667Y420800D01*
X440570Y420634D01*
X440445Y420467D01*
X440320Y420301D01*
X440307Y420287D01*
X440279Y420259D01*
X440237Y420218D01*
X440182Y420176D01*
X440112Y420107D01*
X440015Y420037D01*
X439918Y419954D01*
X439793Y419871D01*
X439655Y419788D01*
X439516Y419704D01*
X439183Y419552D01*
X438795Y419427D01*
X438587Y419385D01*
X438365Y419358D01*
X438212Y420536D01*
X438226D01*
X438254Y420550D01*
X438310Y420564D01*
X438379Y420578D01*
X438462Y420592D01*
X438559Y420620D01*
X438767Y420689D01*
X439017Y420786D01*
X439253Y420911D01*
X439474Y421050D01*
X439669Y421216D01*
X439682Y421244D01*
X439738Y421299D01*
X439807Y421410D01*
X439877Y421549D01*
X439960Y421715D01*
X440029Y421923D01*
X440085Y422159D01*
X440098Y422409D01*
Y422492D01*
X440085Y422547D01*
X440071Y422700D01*
X440029Y422894D01*
X439960Y423116D01*
X439863Y423352D01*
X439724Y423587D01*
X439530Y423809D01*
X439502Y423837D01*
X439419Y423907D01*
X439294Y423990D01*
X439128Y424101D01*
X438920Y424212D01*
X438684Y424295D01*
X438406Y424364D01*
X438101Y424392D01*
X438088D01*
X438060D01*
X438018D01*
X437963Y424378D01*
X437810Y424364D01*
X437630Y424323D01*
X437408Y424267D01*
X437186Y424170D01*
X436964Y424031D01*
X436756Y423851D01*
X436729Y423823D01*
X436673Y423754D01*
X436590Y423643D01*
X436493Y423490D01*
X436396Y423296D01*
X436312Y423060D01*
X436257Y422797D01*
X436229Y422506D01*
Y422381D01*
X436243Y422284D01*
X436257Y422159D01*
X436285Y422020D01*
X436312Y421854D01*
X436354Y421674D01*
X435314Y421812D01*
Y421882D01*
X435328Y421937D01*
Y422117D01*
X435300Y422270D01*
X435272Y422450D01*
X435231Y422658D01*
X435161Y422894D01*
X435064Y423116D01*
X434939Y423352D01*
Y423366D01*
X434926Y423380D01*
X434870Y423449D01*
X434773Y423546D01*
X434648Y423657D01*
X434468Y423768D01*
X434260Y423865D01*
X434024Y423934D01*
X433885Y423962D01*
X433733D01*
X433719D01*
X433705D01*
X433622D01*
X433511Y423934D01*
X433358Y423907D01*
X433192Y423851D01*
X433012Y423782D01*
X432831Y423671D01*
X432665Y423518D01*
X432651Y423504D01*
X432596Y423435D01*
X432526Y423338D01*
X432443Y423213D01*
X432374Y423047D01*
X432304Y422853D01*
X432249Y422631D01*
X432235Y422381D01*
Y422270D01*
X432263Y422145D01*
X432291Y421979D01*
X432346Y421799D01*
X432415Y421618D01*
X432526Y421424D01*
X432665Y421244D01*
X432679Y421230D01*
X432748Y421174D01*
X432845Y421091D01*
X432984Y420994D01*
X433164Y420897D01*
X433386Y420800D01*
X433650Y420717D01*
X433955Y420661D01*
X433747Y419482D01*
X433733D01*
X433691Y419496D01*
X433636Y419510D01*
X433553Y419524D01*
X433456Y419552D01*
X433345Y419593D01*
X433081Y419677D01*
X432776Y419815D01*
X432471Y419982D01*
X432180Y420190D01*
X431916Y420453D01*
X431902Y420467D01*
X431888Y420495D01*
X431861Y420536D01*
X431819Y420592D01*
X431764Y420661D01*
X431708Y420758D01*
X431653Y420855D01*
X431583Y420980D01*
X431472Y421258D01*
X431361Y421577D01*
X431292Y421951D01*
X431264Y422145D01*
Y422492D01*
X431278Y422644D01*
X431306Y422825D01*
X431348Y423047D01*
X431417Y423296D01*
X431500Y423546D01*
X431611Y423796D01*
Y423809D01*
X431625Y423823D01*
X431666Y423907D01*
X431750Y424031D01*
X431847Y424170D01*
X431986Y424336D01*
X432138Y424503D01*
X432318Y424669D01*
X432526Y424808D01*
X432554Y424822D01*
X432623Y424863D01*
X432748Y424919D01*
X432901Y424988D01*
X433081Y425057D01*
X433289Y425113D01*
X433525Y425155D01*
X433761Y425168D01*
X433788D01*
X433872D01*
X433983Y425155D01*
X434135Y425127D01*
X434315Y425085D01*
X434510Y425016D01*
X434704Y424933D01*
X434898Y424822D01*
X434926Y424808D01*
X434981Y424766D01*
X435078Y424683D01*
X435189Y424572D01*
X435314Y424434D01*
X435453Y424267D01*
X435577Y424073D01*
X435702Y423837D01*
Y423851D01*
X435716Y423879D01*
X435730Y423920D01*
X435744Y423976D01*
X435799Y424128D01*
X435882Y424323D01*
X435993Y424544D01*
X436132Y424766D01*
X436312Y424974D01*
X436520Y425168D01*
X436548Y425182D01*
X436631Y425238D01*
X436770Y425321D01*
X436950Y425404D01*
X437172Y425488D01*
X437436Y425571D01*
X437741Y425626D01*
X438074Y425640D01*
X438088D01*
X438129D01*
X438199D01*
X438282Y425626D01*
D02*
G37*
G36*
X440903Y417014D02*
X438906Y415752D01*
X438892D01*
X438864Y415724D01*
X438823Y415696D01*
X438767Y415655D01*
X438615Y415558D01*
X438420Y415433D01*
X438212Y415280D01*
X437990Y415128D01*
X437783Y414975D01*
X437588Y414837D01*
X437574Y414823D01*
X437519Y414781D01*
X437436Y414712D01*
X437339Y414615D01*
X437131Y414407D01*
X437034Y414296D01*
X436950Y414185D01*
X436936Y414171D01*
X436923Y414143D01*
X436895Y414088D01*
X436853Y414004D01*
X436812Y413921D01*
X436770Y413824D01*
X436701Y413602D01*
Y413588D01*
X436687Y413561D01*
Y413505D01*
X436673Y413436D01*
X436659Y413339D01*
Y413228D01*
X436645Y413075D01*
Y411439D01*
X440903D01*
Y410163D01*
X431306D01*
Y414615D01*
X431320Y414726D01*
Y414850D01*
X431334Y415142D01*
X431375Y415447D01*
X431417Y415780D01*
X431486Y416085D01*
X431528Y416237D01*
X431569Y416362D01*
Y416376D01*
X431583Y416390D01*
X431625Y416473D01*
X431680Y416598D01*
X431777Y416750D01*
X431902Y416917D01*
X432069Y417097D01*
X432263Y417263D01*
X432485Y417430D01*
X432499D01*
X432513Y417444D01*
X432596Y417499D01*
X432734Y417555D01*
X432915Y417638D01*
X433123Y417707D01*
X433372Y417777D01*
X433636Y417818D01*
X433927Y417832D01*
X433941D01*
X433969D01*
X434024D01*
X434094Y417818D01*
X434190D01*
X434288Y417804D01*
X434523Y417749D01*
X434801Y417666D01*
X435092Y417555D01*
X435383Y417388D01*
X435522Y417277D01*
X435661Y417166D01*
X435675Y417153D01*
X435688Y417139D01*
X435730Y417097D01*
X435771Y417042D01*
X435827Y416972D01*
X435882Y416889D01*
X435952Y416778D01*
X436035Y416667D01*
X436104Y416529D01*
X436174Y416376D01*
X436257Y416209D01*
X436326Y416029D01*
X436382Y415821D01*
X436451Y415613D01*
X436493Y415377D01*
X436534Y415128D01*
X436548Y415155D01*
X436576Y415211D01*
X436631Y415294D01*
X436687Y415405D01*
X436839Y415655D01*
X436936Y415780D01*
X437020Y415891D01*
X437047Y415918D01*
X437117Y415988D01*
X437228Y416099D01*
X437366Y416237D01*
X437561Y416390D01*
X437769Y416570D01*
X438018Y416750D01*
X438296Y416945D01*
X440903Y418595D01*
Y417014D01*
D02*
G37*
G36*
X286677Y496399D02*
X286788Y496386D01*
X286913Y496358D01*
X287052Y496330D01*
X287204Y496302D01*
X287537Y496191D01*
X287717Y496108D01*
X287884Y496025D01*
X288064Y495914D01*
X288244Y495789D01*
X288425Y495650D01*
X288591Y495484D01*
X288605Y495470D01*
X288633Y495443D01*
X288674Y495387D01*
X288730Y495318D01*
X288799Y495234D01*
X288869Y495123D01*
X288952Y494999D01*
X289021Y494846D01*
X289104Y494694D01*
X289188Y494513D01*
X289257Y494333D01*
X289326Y494125D01*
X289382Y493903D01*
X289423Y493667D01*
X289451Y493432D01*
X289465Y493168D01*
Y493043D01*
X289451Y492960D01*
X289437Y492849D01*
X289423Y492724D01*
X289396Y492586D01*
X289368Y492433D01*
X289285Y492100D01*
X289146Y491754D01*
X289063Y491573D01*
X288966Y491407D01*
X288841Y491240D01*
X288716Y491074D01*
X288702Y491060D01*
X288674Y491032D01*
X288633Y490991D01*
X288577Y490949D01*
X288508Y490880D01*
X288411Y490811D01*
X288314Y490727D01*
X288189Y490644D01*
X288050Y490561D01*
X287912Y490478D01*
X287579Y490325D01*
X287190Y490200D01*
X286982Y490159D01*
X286761Y490131D01*
X286608Y491310D01*
X286622D01*
X286650Y491324D01*
X286705Y491338D01*
X286774Y491351D01*
X286858Y491365D01*
X286955Y491393D01*
X287163Y491462D01*
X287412Y491559D01*
X287648Y491684D01*
X287870Y491823D01*
X288064Y491989D01*
X288078Y492017D01*
X288134Y492072D01*
X288203Y492183D01*
X288272Y492322D01*
X288355Y492489D01*
X288425Y492697D01*
X288480Y492932D01*
X288494Y493182D01*
Y493265D01*
X288480Y493321D01*
X288466Y493473D01*
X288425Y493667D01*
X288355Y493889D01*
X288258Y494125D01*
X288120Y494361D01*
X287925Y494583D01*
X287898Y494610D01*
X287815Y494680D01*
X287690Y494763D01*
X287523Y494874D01*
X287315Y494985D01*
X287080Y495068D01*
X286802Y495137D01*
X286497Y495165D01*
X286483D01*
X286455D01*
X286414D01*
X286358Y495151D01*
X286206Y495137D01*
X286026Y495096D01*
X285804Y495040D01*
X285582Y494943D01*
X285360Y494805D01*
X285152Y494624D01*
X285124Y494596D01*
X285069Y494527D01*
X284985Y494416D01*
X284888Y494264D01*
X284791Y494070D01*
X284708Y493834D01*
X284653Y493570D01*
X284625Y493279D01*
Y493154D01*
X284639Y493057D01*
X284653Y492932D01*
X284680Y492794D01*
X284708Y492627D01*
X284750Y492447D01*
X283710Y492586D01*
Y492655D01*
X283723Y492710D01*
Y492891D01*
X283696Y493043D01*
X283668Y493224D01*
X283626Y493432D01*
X283557Y493667D01*
X283460Y493889D01*
X283335Y494125D01*
Y494139D01*
X283321Y494153D01*
X283266Y494222D01*
X283169Y494319D01*
X283044Y494430D01*
X282864Y494541D01*
X282656Y494638D01*
X282420Y494707D01*
X282281Y494735D01*
X282129D01*
X282115D01*
X282101D01*
X282017D01*
X281907Y494707D01*
X281754Y494680D01*
X281588Y494624D01*
X281407Y494555D01*
X281227Y494444D01*
X281061Y494291D01*
X281047Y494278D01*
X280991Y494208D01*
X280922Y494111D01*
X280839Y493986D01*
X280769Y493820D01*
X280700Y493626D01*
X280644Y493404D01*
X280631Y493154D01*
Y493043D01*
X280658Y492919D01*
X280686Y492752D01*
X280742Y492572D01*
X280811Y492392D01*
X280922Y492197D01*
X281061Y492017D01*
X281075Y492003D01*
X281144Y491948D01*
X281241Y491865D01*
X281380Y491767D01*
X281560Y491670D01*
X281782Y491573D01*
X282045Y491490D01*
X282350Y491435D01*
X282142Y490256D01*
X282129D01*
X282087Y490270D01*
X282031Y490284D01*
X281948Y490297D01*
X281851Y490325D01*
X281740Y490367D01*
X281477Y490450D01*
X281171Y490589D01*
X280866Y490755D01*
X280575Y490963D01*
X280312Y491227D01*
X280298Y491240D01*
X280284Y491268D01*
X280256Y491310D01*
X280215Y491365D01*
X280159Y491435D01*
X280104Y491532D01*
X280048Y491629D01*
X279979Y491754D01*
X279868Y492031D01*
X279757Y492350D01*
X279688Y492724D01*
X279660Y492919D01*
Y493265D01*
X279674Y493418D01*
X279701Y493598D01*
X279743Y493820D01*
X279812Y494070D01*
X279896Y494319D01*
X280007Y494569D01*
Y494583D01*
X280021Y494596D01*
X280062Y494680D01*
X280145Y494805D01*
X280242Y494943D01*
X280381Y495110D01*
X280534Y495276D01*
X280714Y495443D01*
X280922Y495581D01*
X280950Y495595D01*
X281019Y495637D01*
X281144Y495692D01*
X281296Y495761D01*
X281477Y495831D01*
X281685Y495886D01*
X281920Y495928D01*
X282156Y495942D01*
X282184D01*
X282267D01*
X282378Y495928D01*
X282531Y495900D01*
X282711Y495859D01*
X282905Y495789D01*
X283099Y495706D01*
X283293Y495595D01*
X283321Y495581D01*
X283377Y495540D01*
X283474Y495456D01*
X283585Y495345D01*
X283710Y495207D01*
X283848Y495040D01*
X283973Y494846D01*
X284098Y494610D01*
Y494624D01*
X284112Y494652D01*
X284125Y494694D01*
X284139Y494749D01*
X284195Y494902D01*
X284278Y495096D01*
X284389Y495318D01*
X284528Y495540D01*
X284708Y495748D01*
X284916Y495942D01*
X284944Y495956D01*
X285027Y496011D01*
X285166Y496094D01*
X285346Y496177D01*
X285568Y496261D01*
X285831Y496344D01*
X286136Y496399D01*
X286469Y496413D01*
X286483D01*
X286525D01*
X286594D01*
X286677Y496399D01*
D02*
G37*
G36*
X289298Y482489D02*
X289285D01*
X289229D01*
X289146D01*
X289035Y482503D01*
X288910Y482517D01*
X288771Y482545D01*
X288633Y482573D01*
X288480Y482628D01*
X288466D01*
X288452Y482642D01*
X288369Y482670D01*
X288244Y482725D01*
X288078Y482808D01*
X287884Y482919D01*
X287662Y483058D01*
X287440Y483211D01*
X287204Y483405D01*
X287190D01*
X287177Y483433D01*
X287093Y483502D01*
X286968Y483627D01*
X286788Y483807D01*
X286580Y484015D01*
X286331Y484278D01*
X286053Y484597D01*
X285762Y484944D01*
X285748Y484958D01*
X285707Y485014D01*
X285637Y485097D01*
X285554Y485194D01*
X285443Y485319D01*
X285318Y485471D01*
X285180Y485624D01*
X285027Y485804D01*
X284694Y486151D01*
X284361Y486497D01*
X284195Y486664D01*
X284028Y486816D01*
X283876Y486955D01*
X283723Y487066D01*
X283710D01*
X283696Y487094D01*
X283654Y487122D01*
X283598Y487149D01*
X283446Y487246D01*
X283266Y487357D01*
X283044Y487454D01*
X282808Y487551D01*
X282544Y487607D01*
X282295Y487635D01*
X282281D01*
X282267D01*
X282184Y487621D01*
X282045Y487607D01*
X281893Y487565D01*
X281698Y487510D01*
X281504Y487413D01*
X281310Y487288D01*
X281116Y487122D01*
X281088Y487094D01*
X281033Y487024D01*
X280963Y486927D01*
X280866Y486775D01*
X280783Y486581D01*
X280700Y486359D01*
X280644Y486095D01*
X280631Y485804D01*
Y485721D01*
X280644Y485665D01*
X280658Y485499D01*
X280700Y485305D01*
X280756Y485097D01*
X280853Y484861D01*
X280977Y484639D01*
X281144Y484431D01*
X281171Y484403D01*
X281241Y484348D01*
X281352Y484265D01*
X281518Y484181D01*
X281712Y484084D01*
X281962Y484001D01*
X282239Y483946D01*
X282558Y483918D01*
X282434Y482711D01*
X282420D01*
X282378Y482725D01*
X282309D01*
X282212Y482739D01*
X282101Y482767D01*
X281976Y482794D01*
X281823Y482836D01*
X281671Y482878D01*
X281338Y482989D01*
X281005Y483155D01*
X280839Y483252D01*
X280672Y483377D01*
X280520Y483502D01*
X280381Y483641D01*
X280367Y483654D01*
X280353Y483682D01*
X280312Y483724D01*
X280270Y483793D01*
X280215Y483876D01*
X280159Y483973D01*
X280090Y484084D01*
X280021Y484223D01*
X279951Y484375D01*
X279882Y484542D01*
X279826Y484722D01*
X279771Y484916D01*
X279729Y485124D01*
X279688Y485346D01*
X279674Y485582D01*
X279660Y485832D01*
Y485970D01*
X279674Y486068D01*
X279688Y486178D01*
X279701Y486317D01*
X279729Y486470D01*
X279757Y486622D01*
X279854Y486983D01*
X279993Y487343D01*
X280076Y487524D01*
X280173Y487704D01*
X280298Y487870D01*
X280436Y488023D01*
X280450Y488037D01*
X280464Y488064D01*
X280520Y488092D01*
X280575Y488148D01*
X280644Y488217D01*
X280742Y488286D01*
X280839Y488356D01*
X280963Y488439D01*
X281227Y488578D01*
X281560Y488716D01*
X281726Y488772D01*
X281920Y488800D01*
X282115Y488827D01*
X282323Y488841D01*
X282350D01*
X282420D01*
X282531Y488827D01*
X282683Y488813D01*
X282850Y488786D01*
X283044Y488730D01*
X283252Y488675D01*
X283460Y488591D01*
X283488Y488578D01*
X283557Y488550D01*
X283668Y488494D01*
X283820Y488411D01*
X283987Y488300D01*
X284195Y488162D01*
X284403Y487995D01*
X284639Y487801D01*
X284666Y487773D01*
X284750Y487704D01*
X284819Y487635D01*
X284888Y487565D01*
X284972Y487482D01*
X285082Y487371D01*
X285193Y487260D01*
X285318Y487122D01*
X285457Y486983D01*
X285609Y486816D01*
X285762Y486636D01*
X285942Y486442D01*
X286123Y486220D01*
X286317Y485998D01*
X286331Y485984D01*
X286358Y485956D01*
X286400Y485901D01*
X286455Y485832D01*
X286539Y485748D01*
X286622Y485651D01*
X286802Y485429D01*
X287010Y485194D01*
X287218Y484972D01*
X287398Y484778D01*
X287468Y484695D01*
X287537Y484625D01*
X287551Y484611D01*
X287593Y484570D01*
X287648Y484514D01*
X287731Y484445D01*
X287828Y484375D01*
X287925Y484292D01*
X288161Y484126D01*
Y488855D01*
X289298D01*
Y482489D01*
D02*
G37*
G36*
X286331Y481560D02*
X286414Y481533D01*
X286525Y481491D01*
X286650Y481449D01*
X286802Y481394D01*
X286968Y481325D01*
X287149Y481241D01*
X287537Y481047D01*
X287925Y480798D01*
X288120Y480645D01*
X288314Y480492D01*
X288480Y480326D01*
X288647Y480132D01*
X288661Y480118D01*
X288688Y480090D01*
X288716Y480021D01*
X288771Y479952D01*
X288841Y479841D01*
X288910Y479730D01*
X288979Y479577D01*
X289049Y479425D01*
X289132Y479244D01*
X289201Y479050D01*
X289271Y478842D01*
X289340Y478620D01*
X289396Y478384D01*
X289423Y478135D01*
X289451Y477871D01*
X289465Y477594D01*
Y477441D01*
X289451Y477330D01*
Y477206D01*
X289437Y477053D01*
X289409Y476887D01*
X289382Y476692D01*
X289312Y476290D01*
X289201Y475874D01*
X289049Y475458D01*
X288952Y475264D01*
X288841Y475070D01*
X288827Y475056D01*
X288813Y475028D01*
X288771Y474973D01*
X288716Y474917D01*
X288661Y474834D01*
X288577Y474737D01*
X288480Y474626D01*
X288369Y474515D01*
X288244Y474404D01*
X288120Y474279D01*
X287801Y474030D01*
X287426Y473794D01*
X287010Y473586D01*
X286996D01*
X286955Y473558D01*
X286885Y473544D01*
X286802Y473503D01*
X286691Y473475D01*
X286553Y473433D01*
X286400Y473378D01*
X286234Y473336D01*
X286053Y473295D01*
X285845Y473239D01*
X285415Y473170D01*
X284930Y473114D01*
X284431Y473087D01*
X284417D01*
X284361D01*
X284278D01*
X284181Y473101D01*
X284042D01*
X283904Y473114D01*
X283723Y473128D01*
X283543Y473156D01*
X283141Y473225D01*
X282697Y473322D01*
X282253Y473461D01*
X281823Y473655D01*
X281810Y473669D01*
X281768Y473683D01*
X281712Y473711D01*
X281643Y473766D01*
X281546Y473822D01*
X281435Y473891D01*
X281185Y474071D01*
X280908Y474307D01*
X280631Y474584D01*
X280353Y474903D01*
X280117Y475278D01*
X280104Y475292D01*
X280090Y475333D01*
X280062Y475389D01*
X280021Y475458D01*
X279979Y475569D01*
X279937Y475680D01*
X279882Y475819D01*
X279826Y475971D01*
X279771Y476138D01*
X279715Y476318D01*
X279632Y476706D01*
X279563Y477150D01*
X279535Y477608D01*
Y477746D01*
X279549Y477844D01*
X279563Y477968D01*
X279577Y478121D01*
X279591Y478273D01*
X279632Y478454D01*
X279715Y478828D01*
X279840Y479244D01*
X279923Y479452D01*
X280021Y479646D01*
X280145Y479841D01*
X280270Y480035D01*
X280284Y480049D01*
X280298Y480076D01*
X280339Y480132D01*
X280409Y480201D01*
X280478Y480271D01*
X280575Y480368D01*
X280686Y480465D01*
X280797Y480576D01*
X280936Y480686D01*
X281102Y480798D01*
X281269Y480922D01*
X281449Y481033D01*
X281657Y481130D01*
X281865Y481241D01*
X282087Y481325D01*
X282337Y481408D01*
X282628Y480159D01*
X282614D01*
X282586Y480146D01*
X282531Y480118D01*
X282461Y480090D01*
X282378Y480062D01*
X282267Y480021D01*
X282045Y479910D01*
X281796Y479771D01*
X281546Y479605D01*
X281310Y479397D01*
X281102Y479175D01*
X281075Y479147D01*
X281019Y479064D01*
X280950Y478925D01*
X280853Y478745D01*
X280769Y478509D01*
X280686Y478246D01*
X280631Y477927D01*
X280617Y477580D01*
Y477469D01*
X280631Y477400D01*
Y477303D01*
X280644Y477192D01*
X280686Y476928D01*
X280742Y476637D01*
X280839Y476332D01*
X280977Y476013D01*
X281158Y475722D01*
Y475708D01*
X281185Y475694D01*
X281255Y475597D01*
X281366Y475472D01*
X281532Y475320D01*
X281740Y475139D01*
X281976Y474973D01*
X282267Y474820D01*
X282586Y474682D01*
X282600D01*
X282628Y474668D01*
X282669Y474654D01*
X282739Y474640D01*
X282822Y474612D01*
X282919Y474584D01*
X283155Y474543D01*
X283432Y474487D01*
X283737Y474432D01*
X284070Y474404D01*
X284431Y474390D01*
X284445D01*
X284486D01*
X284555D01*
X284639D01*
X284736Y474404D01*
X284860D01*
X284999Y474418D01*
X285152Y474432D01*
X285485Y474473D01*
X285845Y474543D01*
X286206Y474626D01*
X286566Y474737D01*
X286580D01*
X286608Y474751D01*
X286650Y474779D01*
X286719Y474806D01*
X286885Y474890D01*
X287080Y475014D01*
X287301Y475167D01*
X287537Y475361D01*
X287745Y475583D01*
X287939Y475846D01*
Y475860D01*
X287953Y475888D01*
X287981Y475930D01*
X288009Y475985D01*
X288036Y476054D01*
X288078Y476138D01*
X288161Y476332D01*
X288244Y476581D01*
X288314Y476859D01*
X288369Y477164D01*
X288383Y477483D01*
Y477580D01*
X288369Y477663D01*
Y477760D01*
X288355Y477857D01*
X288300Y478107D01*
X288231Y478398D01*
X288120Y478689D01*
X287967Y478995D01*
X287884Y479147D01*
X287773Y479286D01*
X287759Y479300D01*
X287745Y479314D01*
X287704Y479355D01*
X287662Y479411D01*
X287593Y479466D01*
X287509Y479535D01*
X287426Y479619D01*
X287315Y479688D01*
X287190Y479771D01*
X287052Y479868D01*
X286913Y479952D01*
X286747Y480035D01*
X286566Y480104D01*
X286372Y480173D01*
X286164Y480243D01*
X285942Y480298D01*
X286261Y481574D01*
X286275D01*
X286331Y481560D01*
D02*
G37*
G36*
X276548Y489999D02*
X276535D01*
X276479D01*
X276396D01*
X276285Y490013D01*
X276160Y490027D01*
X276021Y490055D01*
X275883Y490082D01*
X275730Y490138D01*
X275716D01*
X275702Y490152D01*
X275619Y490179D01*
X275494Y490235D01*
X275328Y490318D01*
X275134Y490429D01*
X274912Y490568D01*
X274690Y490720D01*
X274454Y490914D01*
X274440D01*
X274427Y490942D01*
X274343Y491012D01*
X274219Y491136D01*
X274038Y491317D01*
X273830Y491525D01*
X273581Y491788D01*
X273303Y492107D01*
X273012Y492454D01*
X272998Y492468D01*
X272957Y492523D01*
X272887Y492607D01*
X272804Y492704D01*
X272693Y492828D01*
X272568Y492981D01*
X272430Y493134D01*
X272277Y493314D01*
X271944Y493661D01*
X271611Y494007D01*
X271445Y494174D01*
X271278Y494326D01*
X271126Y494465D01*
X270973Y494576D01*
X270959D01*
X270946Y494604D01*
X270904Y494631D01*
X270849Y494659D01*
X270696Y494756D01*
X270516Y494867D01*
X270294Y494964D01*
X270058Y495061D01*
X269795Y495117D01*
X269545Y495144D01*
X269531D01*
X269517D01*
X269434Y495131D01*
X269295Y495117D01*
X269143Y495075D01*
X268948Y495020D01*
X268754Y494922D01*
X268560Y494798D01*
X268366Y494631D01*
X268338Y494604D01*
X268283Y494534D01*
X268214Y494437D01*
X268116Y494285D01*
X268033Y494090D01*
X267950Y493868D01*
X267894Y493605D01*
X267881Y493314D01*
Y493231D01*
X267894Y493175D01*
X267908Y493009D01*
X267950Y492814D01*
X268006Y492607D01*
X268103Y492371D01*
X268227Y492149D01*
X268394Y491941D01*
X268421Y491913D01*
X268491Y491858D01*
X268602Y491774D01*
X268768Y491691D01*
X268962Y491594D01*
X269212Y491511D01*
X269489Y491455D01*
X269808Y491428D01*
X269684Y490221D01*
X269670D01*
X269628Y490235D01*
X269559D01*
X269462Y490249D01*
X269351Y490277D01*
X269226Y490304D01*
X269073Y490346D01*
X268921Y490387D01*
X268588Y490499D01*
X268255Y490665D01*
X268089Y490762D01*
X267922Y490887D01*
X267770Y491012D01*
X267631Y491150D01*
X267617Y491164D01*
X267603Y491192D01*
X267562Y491233D01*
X267520Y491303D01*
X267465Y491386D01*
X267409Y491483D01*
X267340Y491594D01*
X267271Y491733D01*
X267201Y491885D01*
X267132Y492052D01*
X267076Y492232D01*
X267021Y492426D01*
X266979Y492634D01*
X266938Y492856D01*
X266924Y493092D01*
X266910Y493341D01*
Y493480D01*
X266924Y493577D01*
X266938Y493688D01*
X266952Y493827D01*
X266979Y493979D01*
X267007Y494132D01*
X267104Y494493D01*
X267243Y494853D01*
X267326Y495033D01*
X267423Y495214D01*
X267548Y495380D01*
X267687Y495533D01*
X267700Y495547D01*
X267714Y495574D01*
X267770Y495602D01*
X267825Y495658D01*
X267894Y495727D01*
X267992Y495796D01*
X268089Y495866D01*
X268214Y495949D01*
X268477Y496087D01*
X268810Y496226D01*
X268976Y496282D01*
X269170Y496309D01*
X269365Y496337D01*
X269573Y496351D01*
X269600D01*
X269670D01*
X269781Y496337D01*
X269933Y496323D01*
X270100Y496296D01*
X270294Y496240D01*
X270502Y496185D01*
X270710Y496101D01*
X270738Y496087D01*
X270807Y496060D01*
X270918Y496004D01*
X271070Y495921D01*
X271237Y495810D01*
X271445Y495671D01*
X271653Y495505D01*
X271889Y495311D01*
X271916Y495283D01*
X272000Y495214D01*
X272069Y495144D01*
X272138Y495075D01*
X272222Y494992D01*
X272332Y494881D01*
X272443Y494770D01*
X272568Y494631D01*
X272707Y494493D01*
X272859Y494326D01*
X273012Y494146D01*
X273192Y493952D01*
X273373Y493730D01*
X273567Y493508D01*
X273581Y493494D01*
X273608Y493466D01*
X273650Y493411D01*
X273705Y493341D01*
X273789Y493258D01*
X273872Y493161D01*
X274052Y492939D01*
X274260Y492704D01*
X274468Y492482D01*
X274648Y492287D01*
X274718Y492204D01*
X274787Y492135D01*
X274801Y492121D01*
X274843Y492080D01*
X274898Y492024D01*
X274981Y491955D01*
X275078Y491885D01*
X275175Y491802D01*
X275411Y491636D01*
Y496365D01*
X276548D01*
Y489999D01*
D02*
G37*
G36*
Y482538D02*
X276535D01*
X276479D01*
X276396D01*
X276285Y482552D01*
X276160Y482566D01*
X276021Y482593D01*
X275883Y482621D01*
X275730Y482677D01*
X275716D01*
X275702Y482691D01*
X275619Y482718D01*
X275494Y482774D01*
X275328Y482857D01*
X275134Y482968D01*
X274912Y483107D01*
X274690Y483259D01*
X274454Y483453D01*
X274440D01*
X274427Y483481D01*
X274343Y483550D01*
X274219Y483675D01*
X274038Y483856D01*
X273830Y484063D01*
X273581Y484327D01*
X273303Y484646D01*
X273012Y484993D01*
X272998Y485007D01*
X272957Y485062D01*
X272887Y485145D01*
X272804Y485242D01*
X272693Y485367D01*
X272568Y485520D01*
X272430Y485672D01*
X272277Y485853D01*
X271944Y486199D01*
X271611Y486546D01*
X271445Y486712D01*
X271278Y486865D01*
X271126Y487004D01*
X270973Y487115D01*
X270959D01*
X270946Y487142D01*
X270904Y487170D01*
X270849Y487198D01*
X270696Y487295D01*
X270516Y487406D01*
X270294Y487503D01*
X270058Y487600D01*
X269795Y487655D01*
X269545Y487683D01*
X269531D01*
X269517D01*
X269434Y487669D01*
X269295Y487655D01*
X269143Y487614D01*
X268948Y487558D01*
X268754Y487461D01*
X268560Y487337D01*
X268366Y487170D01*
X268338Y487142D01*
X268283Y487073D01*
X268214Y486976D01*
X268116Y486823D01*
X268033Y486629D01*
X267950Y486407D01*
X267894Y486144D01*
X267881Y485853D01*
Y485769D01*
X267894Y485714D01*
X267908Y485547D01*
X267950Y485353D01*
X268006Y485145D01*
X268103Y484910D01*
X268227Y484688D01*
X268394Y484480D01*
X268421Y484452D01*
X268491Y484396D01*
X268602Y484313D01*
X268768Y484230D01*
X268962Y484133D01*
X269212Y484050D01*
X269489Y483994D01*
X269808Y483966D01*
X269684Y482760D01*
X269670D01*
X269628Y482774D01*
X269559D01*
X269462Y482788D01*
X269351Y482815D01*
X269226Y482843D01*
X269073Y482885D01*
X268921Y482926D01*
X268588Y483037D01*
X268255Y483204D01*
X268089Y483301D01*
X267922Y483426D01*
X267770Y483550D01*
X267631Y483689D01*
X267617Y483703D01*
X267603Y483731D01*
X267562Y483772D01*
X267520Y483842D01*
X267465Y483925D01*
X267409Y484022D01*
X267340Y484133D01*
X267271Y484272D01*
X267201Y484424D01*
X267132Y484590D01*
X267076Y484771D01*
X267021Y484965D01*
X266979Y485173D01*
X266938Y485395D01*
X266924Y485631D01*
X266910Y485880D01*
Y486019D01*
X266924Y486116D01*
X266938Y486227D01*
X266952Y486366D01*
X266979Y486518D01*
X267007Y486671D01*
X267104Y487031D01*
X267243Y487392D01*
X267326Y487572D01*
X267423Y487752D01*
X267548Y487919D01*
X267687Y488072D01*
X267700Y488085D01*
X267714Y488113D01*
X267770Y488141D01*
X267825Y488196D01*
X267894Y488266D01*
X267992Y488335D01*
X268089Y488404D01*
X268214Y488488D01*
X268477Y488626D01*
X268810Y488765D01*
X268976Y488820D01*
X269170Y488848D01*
X269365Y488876D01*
X269573Y488890D01*
X269600D01*
X269670D01*
X269781Y488876D01*
X269933Y488862D01*
X270100Y488834D01*
X270294Y488779D01*
X270502Y488723D01*
X270710Y488640D01*
X270738Y488626D01*
X270807Y488599D01*
X270918Y488543D01*
X271070Y488460D01*
X271237Y488349D01*
X271445Y488210D01*
X271653Y488044D01*
X271889Y487850D01*
X271916Y487822D01*
X272000Y487752D01*
X272069Y487683D01*
X272138Y487614D01*
X272222Y487531D01*
X272332Y487420D01*
X272443Y487309D01*
X272568Y487170D01*
X272707Y487031D01*
X272859Y486865D01*
X273012Y486685D01*
X273192Y486491D01*
X273373Y486269D01*
X273567Y486047D01*
X273581Y486033D01*
X273608Y486005D01*
X273650Y485950D01*
X273705Y485880D01*
X273789Y485797D01*
X273872Y485700D01*
X274052Y485478D01*
X274260Y485242D01*
X274468Y485020D01*
X274648Y484826D01*
X274718Y484743D01*
X274787Y484674D01*
X274801Y484660D01*
X274843Y484618D01*
X274898Y484563D01*
X274981Y484493D01*
X275078Y484424D01*
X275175Y484341D01*
X275411Y484174D01*
Y488904D01*
X276548D01*
Y482538D01*
D02*
G37*
G36*
X273581Y481609D02*
X273664Y481581D01*
X273775Y481539D01*
X273900Y481498D01*
X274052Y481442D01*
X274219Y481373D01*
X274399Y481290D01*
X274787Y481096D01*
X275175Y480846D01*
X275370Y480694D01*
X275564Y480541D01*
X275730Y480374D01*
X275897Y480180D01*
X275910Y480167D01*
X275938Y480139D01*
X275966Y480069D01*
X276021Y480000D01*
X276091Y479889D01*
X276160Y479778D01*
X276229Y479626D01*
X276299Y479473D01*
X276382Y479293D01*
X276451Y479099D01*
X276521Y478891D01*
X276590Y478669D01*
X276646Y478433D01*
X276673Y478183D01*
X276701Y477920D01*
X276715Y477643D01*
Y477490D01*
X276701Y477379D01*
Y477254D01*
X276687Y477102D01*
X276659Y476935D01*
X276632Y476741D01*
X276562Y476339D01*
X276451Y475923D01*
X276299Y475507D01*
X276202Y475313D01*
X276091Y475118D01*
X276077Y475104D01*
X276063Y475077D01*
X276021Y475021D01*
X275966Y474966D01*
X275910Y474883D01*
X275827Y474786D01*
X275730Y474675D01*
X275619Y474564D01*
X275494Y474453D01*
X275370Y474328D01*
X275051Y474078D01*
X274676Y473843D01*
X274260Y473634D01*
X274246D01*
X274205Y473607D01*
X274135Y473593D01*
X274052Y473551D01*
X273941Y473523D01*
X273803Y473482D01*
X273650Y473427D01*
X273484Y473385D01*
X273303Y473343D01*
X273095Y473288D01*
X272665Y473218D01*
X272180Y473163D01*
X271681Y473135D01*
X271667D01*
X271611D01*
X271528D01*
X271431Y473149D01*
X271292D01*
X271154Y473163D01*
X270973Y473177D01*
X270793Y473205D01*
X270391Y473274D01*
X269947Y473371D01*
X269503Y473510D01*
X269073Y473704D01*
X269060Y473718D01*
X269018Y473732D01*
X268962Y473759D01*
X268893Y473815D01*
X268796Y473870D01*
X268685Y473940D01*
X268435Y474120D01*
X268158Y474356D01*
X267881Y474633D01*
X267603Y474952D01*
X267367Y475326D01*
X267354Y475340D01*
X267340Y475382D01*
X267312Y475437D01*
X267271Y475507D01*
X267229Y475618D01*
X267187Y475729D01*
X267132Y475867D01*
X267076Y476020D01*
X267021Y476186D01*
X266965Y476367D01*
X266882Y476755D01*
X266813Y477199D01*
X266785Y477656D01*
Y477795D01*
X266799Y477892D01*
X266813Y478017D01*
X266827Y478170D01*
X266840Y478322D01*
X266882Y478502D01*
X266965Y478877D01*
X267090Y479293D01*
X267173Y479501D01*
X267271Y479695D01*
X267395Y479889D01*
X267520Y480083D01*
X267534Y480097D01*
X267548Y480125D01*
X267589Y480180D01*
X267659Y480250D01*
X267728Y480319D01*
X267825Y480416D01*
X267936Y480513D01*
X268047Y480624D01*
X268186Y480735D01*
X268352Y480846D01*
X268519Y480971D01*
X268699Y481082D01*
X268907Y481179D01*
X269115Y481290D01*
X269337Y481373D01*
X269587Y481456D01*
X269878Y480208D01*
X269864D01*
X269836Y480194D01*
X269781Y480167D01*
X269711Y480139D01*
X269628Y480111D01*
X269517Y480069D01*
X269295Y479958D01*
X269046Y479820D01*
X268796Y479653D01*
X268560Y479445D01*
X268352Y479224D01*
X268325Y479196D01*
X268269Y479113D01*
X268200Y478974D01*
X268103Y478793D01*
X268019Y478558D01*
X267936Y478294D01*
X267881Y477975D01*
X267867Y477629D01*
Y477518D01*
X267881Y477448D01*
Y477351D01*
X267894Y477240D01*
X267936Y476977D01*
X267992Y476685D01*
X268089Y476380D01*
X268227Y476062D01*
X268408Y475770D01*
Y475756D01*
X268435Y475742D01*
X268505Y475645D01*
X268616Y475521D01*
X268782Y475368D01*
X268990Y475188D01*
X269226Y475021D01*
X269517Y474869D01*
X269836Y474730D01*
X269850D01*
X269878Y474716D01*
X269919Y474702D01*
X269989Y474688D01*
X270072Y474661D01*
X270169Y474633D01*
X270405Y474591D01*
X270682Y474536D01*
X270987Y474481D01*
X271320Y474453D01*
X271681Y474439D01*
X271695D01*
X271736D01*
X271805D01*
X271889D01*
X271986Y474453D01*
X272111D01*
X272249Y474467D01*
X272402Y474481D01*
X272735Y474522D01*
X273095Y474591D01*
X273456Y474675D01*
X273816Y474786D01*
X273830D01*
X273858Y474799D01*
X273900Y474827D01*
X273969Y474855D01*
X274135Y474938D01*
X274329Y475063D01*
X274551Y475215D01*
X274787Y475410D01*
X274995Y475631D01*
X275189Y475895D01*
Y475909D01*
X275203Y475937D01*
X275231Y475978D01*
X275259Y476034D01*
X275286Y476103D01*
X275328Y476186D01*
X275411Y476380D01*
X275494Y476630D01*
X275564Y476907D01*
X275619Y477212D01*
X275633Y477532D01*
Y477629D01*
X275619Y477712D01*
Y477809D01*
X275605Y477906D01*
X275550Y478156D01*
X275481Y478447D01*
X275370Y478738D01*
X275217Y479043D01*
X275134Y479196D01*
X275023Y479334D01*
X275009Y479348D01*
X274995Y479362D01*
X274954Y479404D01*
X274912Y479459D01*
X274843Y479515D01*
X274759Y479584D01*
X274676Y479667D01*
X274565Y479737D01*
X274440Y479820D01*
X274302Y479917D01*
X274163Y480000D01*
X273997Y480083D01*
X273816Y480153D01*
X273622Y480222D01*
X273414Y480291D01*
X273192Y480347D01*
X273511Y481623D01*
X273525D01*
X273581Y481609D01*
D02*
G37*
G36*
X230934Y470895D02*
X233236D01*
Y469716D01*
X230934D01*
Y465542D01*
X229852D01*
X223639Y469938D01*
Y470895D01*
X229852D01*
Y472198D01*
X230934D01*
Y470895D01*
D02*
G37*
G36*
X230615Y464765D02*
X230726Y464751D01*
X230851Y464723D01*
X230989Y464696D01*
X231142Y464668D01*
X231475Y464557D01*
X231655Y464474D01*
X231821Y464390D01*
X232002Y464280D01*
X232182Y464155D01*
X232362Y464016D01*
X232529Y463850D01*
X232543Y463836D01*
X232570Y463808D01*
X232612Y463753D01*
X232667Y463683D01*
X232737Y463600D01*
X232806Y463489D01*
X232889Y463364D01*
X232959Y463212D01*
X233042Y463059D01*
X233125Y462879D01*
X233194Y462699D01*
X233264Y462491D01*
X233319Y462269D01*
X233361Y462033D01*
X233389Y461797D01*
X233403Y461534D01*
Y461409D01*
X233389Y461326D01*
X233375Y461215D01*
X233361Y461090D01*
X233333Y460951D01*
X233305Y460799D01*
X233222Y460466D01*
X233083Y460119D01*
X233000Y459939D01*
X232903Y459772D01*
X232778Y459606D01*
X232654Y459440D01*
X232640Y459426D01*
X232612Y459398D01*
X232570Y459356D01*
X232515Y459315D01*
X232446Y459245D01*
X232348Y459176D01*
X232251Y459093D01*
X232127Y459010D01*
X231988Y458926D01*
X231849Y458843D01*
X231516Y458691D01*
X231128Y458566D01*
X230920Y458524D01*
X230698Y458496D01*
X230546Y459675D01*
X230559D01*
X230587Y459689D01*
X230643Y459703D01*
X230712Y459717D01*
X230795Y459731D01*
X230892Y459758D01*
X231100Y459828D01*
X231350Y459925D01*
X231586Y460050D01*
X231808Y460188D01*
X232002Y460355D01*
X232016Y460382D01*
X232071Y460438D01*
X232140Y460549D01*
X232210Y460688D01*
X232293Y460854D01*
X232362Y461062D01*
X232418Y461298D01*
X232432Y461548D01*
Y461631D01*
X232418Y461686D01*
X232404Y461839D01*
X232362Y462033D01*
X232293Y462255D01*
X232196Y462491D01*
X232057Y462726D01*
X231863Y462948D01*
X231835Y462976D01*
X231752Y463045D01*
X231627Y463129D01*
X231461Y463239D01*
X231253Y463350D01*
X231017Y463434D01*
X230740Y463503D01*
X230435Y463531D01*
X230421D01*
X230393D01*
X230351D01*
X230296Y463517D01*
X230143Y463503D01*
X229963Y463461D01*
X229741Y463406D01*
X229519Y463309D01*
X229297Y463170D01*
X229089Y462990D01*
X229062Y462962D01*
X229006Y462893D01*
X228923Y462782D01*
X228826Y462629D01*
X228729Y462435D01*
X228646Y462199D01*
X228590Y461936D01*
X228562Y461645D01*
Y461520D01*
X228576Y461423D01*
X228590Y461298D01*
X228618Y461159D01*
X228646Y460993D01*
X228687Y460812D01*
X227647Y460951D01*
Y461021D01*
X227661Y461076D01*
Y461256D01*
X227633Y461409D01*
X227605Y461589D01*
X227564Y461797D01*
X227495Y462033D01*
X227397Y462255D01*
X227273Y462491D01*
Y462504D01*
X227259Y462518D01*
X227203Y462588D01*
X227106Y462685D01*
X226981Y462796D01*
X226801Y462907D01*
X226593Y463004D01*
X226357Y463073D01*
X226219Y463101D01*
X226066D01*
X226052D01*
X226038D01*
X225955D01*
X225844Y463073D01*
X225692Y463045D01*
X225525Y462990D01*
X225345Y462920D01*
X225165Y462809D01*
X224998Y462657D01*
X224984Y462643D01*
X224929Y462574D01*
X224860Y462477D01*
X224776Y462352D01*
X224707Y462185D01*
X224638Y461991D01*
X224582Y461769D01*
X224568Y461520D01*
Y461409D01*
X224596Y461284D01*
X224624Y461118D01*
X224679Y460937D01*
X224749Y460757D01*
X224860Y460563D01*
X224998Y460382D01*
X225012Y460369D01*
X225081Y460313D01*
X225179Y460230D01*
X225317Y460133D01*
X225497Y460036D01*
X225719Y459939D01*
X225983Y459855D01*
X226288Y459800D01*
X226080Y458621D01*
X226066D01*
X226024Y458635D01*
X225969Y458649D01*
X225886Y458663D01*
X225789Y458691D01*
X225678Y458732D01*
X225414Y458815D01*
X225109Y458954D01*
X224804Y459120D01*
X224513Y459328D01*
X224249Y459592D01*
X224235Y459606D01*
X224222Y459634D01*
X224194Y459675D01*
X224152Y459731D01*
X224097Y459800D01*
X224041Y459897D01*
X223986Y459994D01*
X223916Y460119D01*
X223806Y460396D01*
X223695Y460715D01*
X223625Y461090D01*
X223598Y461284D01*
Y461631D01*
X223611Y461783D01*
X223639Y461964D01*
X223681Y462185D01*
X223750Y462435D01*
X223833Y462685D01*
X223944Y462934D01*
Y462948D01*
X223958Y462962D01*
X224000Y463045D01*
X224083Y463170D01*
X224180Y463309D01*
X224319Y463475D01*
X224471Y463642D01*
X224652Y463808D01*
X224860Y463947D01*
X224887Y463961D01*
X224957Y464002D01*
X225081Y464058D01*
X225234Y464127D01*
X225414Y464196D01*
X225622Y464252D01*
X225858Y464293D01*
X226094Y464307D01*
X226122D01*
X226205D01*
X226316Y464293D01*
X226468Y464266D01*
X226649Y464224D01*
X226843Y464155D01*
X227037Y464072D01*
X227231Y463961D01*
X227259Y463947D01*
X227314Y463905D01*
X227411Y463822D01*
X227522Y463711D01*
X227647Y463572D01*
X227786Y463406D01*
X227911Y463212D01*
X228035Y462976D01*
Y462990D01*
X228049Y463018D01*
X228063Y463059D01*
X228077Y463115D01*
X228132Y463267D01*
X228216Y463461D01*
X228327Y463683D01*
X228465Y463905D01*
X228646Y464113D01*
X228854Y464307D01*
X228881Y464321D01*
X228965Y464377D01*
X229103Y464460D01*
X229284Y464543D01*
X229505Y464626D01*
X229769Y464710D01*
X230074Y464765D01*
X230407Y464779D01*
X230421D01*
X230462D01*
X230532D01*
X230615Y464765D01*
D02*
G37*
G36*
X233236Y456153D02*
X231239Y454891D01*
X231225D01*
X231197Y454863D01*
X231156Y454835D01*
X231100Y454794D01*
X230948Y454697D01*
X230754Y454572D01*
X230546Y454419D01*
X230324Y454267D01*
X230116Y454114D01*
X229921Y453975D01*
X229908Y453961D01*
X229852Y453920D01*
X229769Y453851D01*
X229672Y453753D01*
X229464Y453545D01*
X229367Y453434D01*
X229284Y453324D01*
X229270Y453310D01*
X229256Y453282D01*
X229228Y453226D01*
X229186Y453143D01*
X229145Y453060D01*
X229103Y452963D01*
X229034Y452741D01*
Y452727D01*
X229020Y452699D01*
Y452644D01*
X229006Y452575D01*
X228992Y452477D01*
Y452367D01*
X228978Y452214D01*
Y450578D01*
X233236D01*
Y449302D01*
X223639D01*
Y453753D01*
X223653Y453864D01*
Y453989D01*
X223667Y454280D01*
X223708Y454585D01*
X223750Y454918D01*
X223819Y455224D01*
X223861Y455376D01*
X223903Y455501D01*
Y455515D01*
X223916Y455529D01*
X223958Y455612D01*
X224014Y455737D01*
X224111Y455889D01*
X224235Y456056D01*
X224402Y456236D01*
X224596Y456402D01*
X224818Y456569D01*
X224832D01*
X224846Y456583D01*
X224929Y456638D01*
X225068Y456693D01*
X225248Y456777D01*
X225456Y456846D01*
X225706Y456915D01*
X225969Y456957D01*
X226260Y456971D01*
X226274D01*
X226302D01*
X226357D01*
X226427Y456957D01*
X226524D01*
X226621Y456943D01*
X226857Y456888D01*
X227134Y456805D01*
X227425Y456693D01*
X227716Y456527D01*
X227855Y456416D01*
X227994Y456305D01*
X228008Y456291D01*
X228022Y456278D01*
X228063Y456236D01*
X228105Y456180D01*
X228160Y456111D01*
X228216Y456028D01*
X228285Y455917D01*
X228368Y455806D01*
X228438Y455667D01*
X228507Y455515D01*
X228590Y455348D01*
X228659Y455168D01*
X228715Y454960D01*
X228784Y454752D01*
X228826Y454516D01*
X228867Y454267D01*
X228881Y454294D01*
X228909Y454350D01*
X228965Y454433D01*
X229020Y454544D01*
X229173Y454794D01*
X229270Y454918D01*
X229353Y455029D01*
X229381Y455057D01*
X229450Y455126D01*
X229561Y455237D01*
X229700Y455376D01*
X229894Y455529D01*
X230102Y455709D01*
X230351Y455889D01*
X230629Y456083D01*
X233236Y457734D01*
Y456153D01*
D02*
G37*
G36*
X126866Y456889D02*
X126977Y456875D01*
X127116Y456861D01*
X127269Y456833D01*
X127421Y456805D01*
X127782Y456708D01*
X128142Y456570D01*
X128323Y456486D01*
X128503Y456389D01*
X128669Y456264D01*
X128822Y456126D01*
X128836Y456112D01*
X128863Y456098D01*
X128891Y456043D01*
X128947Y455987D01*
X129016Y455918D01*
X129085Y455821D01*
X129155Y455724D01*
X129238Y455599D01*
X129377Y455335D01*
X129515Y455003D01*
X129571Y454836D01*
X129599Y454642D01*
X129626Y454448D01*
X129640Y454240D01*
Y454212D01*
Y454143D01*
X129626Y454032D01*
X129612Y453879D01*
X129585Y453713D01*
X129529Y453519D01*
X129474Y453311D01*
X129390Y453102D01*
X129377Y453075D01*
X129349Y453005D01*
X129293Y452895D01*
X129210Y452742D01*
X129099Y452575D01*
X128961Y452368D01*
X128794Y452160D01*
X128600Y451924D01*
X128572Y451896D01*
X128503Y451813D01*
X128434Y451743D01*
X128364Y451674D01*
X128281Y451591D01*
X128170Y451480D01*
X128059Y451369D01*
X127920Y451244D01*
X127782Y451105D01*
X127615Y450953D01*
X127435Y450800D01*
X127241Y450620D01*
X127019Y450440D01*
X126797Y450246D01*
X126783Y450232D01*
X126755Y450204D01*
X126700Y450162D01*
X126631Y450107D01*
X126547Y450024D01*
X126450Y449941D01*
X126228Y449760D01*
X125993Y449552D01*
X125771Y449344D01*
X125577Y449164D01*
X125493Y449095D01*
X125424Y449025D01*
X125410Y449011D01*
X125369Y448970D01*
X125313Y448914D01*
X125244Y448831D01*
X125175Y448734D01*
X125091Y448637D01*
X124925Y448401D01*
X129654D01*
Y447264D01*
X123288D01*
Y447278D01*
Y447333D01*
Y447416D01*
X123302Y447528D01*
X123316Y447652D01*
X123344Y447791D01*
X123372Y447930D01*
X123427Y448082D01*
Y448096D01*
X123441Y448110D01*
X123469Y448193D01*
X123524Y448318D01*
X123607Y448484D01*
X123718Y448679D01*
X123857Y448900D01*
X124010Y449122D01*
X124204Y449358D01*
Y449372D01*
X124231Y449386D01*
X124301Y449469D01*
X124426Y449594D01*
X124606Y449774D01*
X124814Y449982D01*
X125077Y450232D01*
X125396Y450509D01*
X125743Y450800D01*
X125757Y450814D01*
X125812Y450856D01*
X125896Y450925D01*
X125993Y451008D01*
X126117Y451119D01*
X126270Y451244D01*
X126423Y451383D01*
X126603Y451535D01*
X126950Y451868D01*
X127296Y452201D01*
X127463Y452368D01*
X127615Y452534D01*
X127754Y452687D01*
X127865Y452839D01*
Y452853D01*
X127893Y452867D01*
X127920Y452908D01*
X127948Y452964D01*
X128045Y453116D01*
X128156Y453297D01*
X128253Y453519D01*
X128350Y453754D01*
X128406Y454018D01*
X128434Y454268D01*
Y454281D01*
Y454295D01*
X128420Y454378D01*
X128406Y454517D01*
X128364Y454670D01*
X128309Y454864D01*
X128212Y455058D01*
X128087Y455252D01*
X127920Y455446D01*
X127893Y455474D01*
X127823Y455530D01*
X127726Y455599D01*
X127574Y455696D01*
X127380Y455779D01*
X127158Y455862D01*
X126894Y455918D01*
X126603Y455932D01*
X126520D01*
X126464Y455918D01*
X126298Y455904D01*
X126104Y455862D01*
X125896Y455807D01*
X125660Y455710D01*
X125438Y455585D01*
X125230Y455419D01*
X125202Y455391D01*
X125147Y455322D01*
X125063Y455210D01*
X124980Y455044D01*
X124883Y454850D01*
X124800Y454600D01*
X124745Y454323D01*
X124717Y454004D01*
X123510Y454129D01*
Y454143D01*
X123524Y454184D01*
Y454254D01*
X123538Y454351D01*
X123566Y454462D01*
X123594Y454586D01*
X123635Y454739D01*
X123677Y454892D01*
X123788Y455224D01*
X123954Y455557D01*
X124051Y455724D01*
X124176Y455890D01*
X124301Y456043D01*
X124439Y456181D01*
X124453Y456195D01*
X124481Y456209D01*
X124523Y456251D01*
X124592Y456292D01*
X124675Y456348D01*
X124772Y456403D01*
X124883Y456473D01*
X125022Y456542D01*
X125175Y456611D01*
X125341Y456681D01*
X125521Y456736D01*
X125715Y456791D01*
X125923Y456833D01*
X126145Y456875D01*
X126381Y456889D01*
X126631Y456903D01*
X126769D01*
X126866Y456889D01*
D02*
G37*
G36*
X118837Y456847D02*
X118961D01*
X119253Y456833D01*
X119558Y456791D01*
X119891Y456750D01*
X120196Y456681D01*
X120348Y456639D01*
X120473Y456597D01*
X120487D01*
X120501Y456584D01*
X120584Y456542D01*
X120709Y456486D01*
X120861Y456389D01*
X121028Y456264D01*
X121208Y456098D01*
X121375Y455904D01*
X121541Y455682D01*
Y455668D01*
X121555Y455654D01*
X121610Y455571D01*
X121666Y455432D01*
X121749Y455252D01*
X121818Y455044D01*
X121888Y454795D01*
X121929Y454531D01*
X121943Y454240D01*
Y454226D01*
Y454198D01*
Y454143D01*
X121929Y454073D01*
Y453976D01*
X121915Y453879D01*
X121860Y453643D01*
X121777Y453366D01*
X121666Y453075D01*
X121499Y452784D01*
X121388Y452645D01*
X121277Y452506D01*
X121264Y452492D01*
X121250Y452478D01*
X121208Y452437D01*
X121153Y452395D01*
X121083Y452340D01*
X121000Y452284D01*
X120889Y452215D01*
X120778Y452132D01*
X120639Y452062D01*
X120487Y451993D01*
X120321Y451910D01*
X120140Y451841D01*
X119932Y451785D01*
X119724Y451716D01*
X119488Y451674D01*
X119239Y451632D01*
X119267Y451619D01*
X119322Y451591D01*
X119405Y451535D01*
X119516Y451480D01*
X119766Y451327D01*
X119891Y451230D01*
X120001Y451147D01*
X120029Y451119D01*
X120099Y451050D01*
X120210Y450939D01*
X120348Y450800D01*
X120501Y450606D01*
X120681Y450398D01*
X120861Y450149D01*
X121055Y449871D01*
X122706Y447264D01*
X121125D01*
X119863Y449261D01*
Y449275D01*
X119835Y449303D01*
X119807Y449344D01*
X119766Y449400D01*
X119669Y449552D01*
X119544Y449746D01*
X119391Y449954D01*
X119239Y450176D01*
X119086Y450384D01*
X118947Y450578D01*
X118934Y450592D01*
X118892Y450648D01*
X118823Y450731D01*
X118726Y450828D01*
X118518Y451036D01*
X118407Y451133D01*
X118296Y451216D01*
X118282Y451230D01*
X118254Y451244D01*
X118199Y451272D01*
X118115Y451314D01*
X118032Y451355D01*
X117935Y451397D01*
X117713Y451466D01*
X117699D01*
X117672Y451480D01*
X117616D01*
X117547Y451494D01*
X117450Y451508D01*
X117339D01*
X117186Y451522D01*
X115550D01*
Y447264D01*
X114274D01*
Y456861D01*
X118726D01*
X118837Y456847D01*
D02*
G37*
G36*
X134244Y456889D02*
X134355Y456875D01*
X134480Y456861D01*
X134619Y456847D01*
X134757Y456805D01*
X135090Y456722D01*
X135423Y456597D01*
X135590Y456514D01*
X135756Y456417D01*
X135909Y456292D01*
X136061Y456167D01*
X136075Y456154D01*
X136089Y456140D01*
X136131Y456098D01*
X136186Y456043D01*
X136241Y455959D01*
X136311Y455876D01*
X136449Y455668D01*
X136588Y455405D01*
X136713Y455100D01*
X136810Y454753D01*
X136824Y454573D01*
X136838Y454378D01*
Y454365D01*
Y454351D01*
Y454268D01*
X136824Y454143D01*
X136796Y453990D01*
X136755Y453796D01*
X136685Y453602D01*
X136602Y453408D01*
X136477Y453214D01*
X136463Y453186D01*
X136408Y453130D01*
X136325Y453047D01*
X136214Y452936D01*
X136061Y452811D01*
X135881Y452687D01*
X135673Y452562D01*
X135423Y452451D01*
X135437D01*
X135465Y452437D01*
X135506Y452423D01*
X135562Y452395D01*
X135728Y452326D01*
X135922Y452229D01*
X136131Y452090D01*
X136352Y451938D01*
X136560Y451743D01*
X136755Y451522D01*
Y451508D01*
X136768Y451494D01*
X136824Y451411D01*
X136907Y451272D01*
X136990Y451092D01*
X137073Y450870D01*
X137157Y450606D01*
X137212Y450315D01*
X137226Y449996D01*
Y449982D01*
Y449941D01*
Y449871D01*
X137212Y449788D01*
X137198Y449691D01*
X137184Y449566D01*
X137157Y449427D01*
X137115Y449275D01*
X137018Y448956D01*
X136949Y448776D01*
X136852Y448609D01*
X136755Y448429D01*
X136644Y448262D01*
X136505Y448096D01*
X136352Y447930D01*
X136339Y447916D01*
X136311Y447888D01*
X136269Y447846D01*
X136200Y447805D01*
X136103Y447735D01*
X136006Y447666D01*
X135881Y447597D01*
X135742Y447514D01*
X135590Y447430D01*
X135409Y447361D01*
X135215Y447292D01*
X135021Y447222D01*
X134799Y447181D01*
X134563Y447139D01*
X134328Y447111D01*
X134064Y447098D01*
X133925D01*
X133828Y447111D01*
X133703Y447125D01*
X133565Y447139D01*
X133412Y447167D01*
X133246Y447209D01*
X132871Y447306D01*
X132677Y447375D01*
X132497Y447444D01*
X132303Y447541D01*
X132109Y447652D01*
X131928Y447777D01*
X131762Y447930D01*
X131748Y447943D01*
X131720Y447971D01*
X131679Y448013D01*
X131623Y448082D01*
X131568Y448165D01*
X131485Y448262D01*
X131415Y448373D01*
X131332Y448512D01*
X131249Y448651D01*
X131180Y448817D01*
X131041Y449164D01*
X130985Y449372D01*
X130944Y449580D01*
X130916Y449802D01*
X130902Y450024D01*
Y450038D01*
Y450065D01*
Y450121D01*
X130916Y450176D01*
Y450260D01*
X130930Y450357D01*
X130958Y450578D01*
X131013Y450828D01*
X131096Y451078D01*
X131221Y451341D01*
X131374Y451591D01*
Y451605D01*
X131401Y451619D01*
X131457Y451688D01*
X131568Y451799D01*
X131720Y451938D01*
X131915Y452076D01*
X132150Y452229D01*
X132414Y452354D01*
X132733Y452451D01*
X132719D01*
X132705Y452465D01*
X132663Y452478D01*
X132608Y452506D01*
X132483Y452562D01*
X132317Y452645D01*
X132136Y452756D01*
X131956Y452895D01*
X131790Y453047D01*
X131637Y453214D01*
X131623Y453241D01*
X131582Y453297D01*
X131526Y453408D01*
X131471Y453546D01*
X131401Y453727D01*
X131346Y453935D01*
X131304Y454170D01*
X131290Y454420D01*
Y454434D01*
Y454462D01*
Y454517D01*
X131304Y454600D01*
X131318Y454683D01*
X131332Y454795D01*
X131388Y455030D01*
X131471Y455308D01*
X131609Y455599D01*
X131693Y455751D01*
X131790Y455904D01*
X131915Y456043D01*
X132039Y456181D01*
X132053Y456195D01*
X132081Y456209D01*
X132122Y456251D01*
X132178Y456292D01*
X132247Y456348D01*
X132344Y456403D01*
X132455Y456473D01*
X132566Y456542D01*
X132705Y456611D01*
X132858Y456681D01*
X133024Y456736D01*
X133204Y456791D01*
X133593Y456875D01*
X133814Y456889D01*
X134036Y456903D01*
X134161D01*
X134244Y456889D01*
D02*
G37*
G36*
X165719Y455724D02*
X165705Y455710D01*
X165678Y455682D01*
X165622Y455627D01*
X165567Y455543D01*
X165483Y455446D01*
X165373Y455335D01*
X165261Y455197D01*
X165137Y455030D01*
X165012Y454864D01*
X164859Y454670D01*
X164707Y454448D01*
X164554Y454226D01*
X164388Y453976D01*
X164221Y453713D01*
X164055Y453422D01*
X163888Y453130D01*
X163875Y453116D01*
X163847Y453061D01*
X163805Y452978D01*
X163736Y452853D01*
X163667Y452700D01*
X163583Y452534D01*
X163486Y452340D01*
X163389Y452118D01*
X163278Y451868D01*
X163153Y451619D01*
X163043Y451341D01*
X162932Y451050D01*
X162710Y450454D01*
X162502Y449816D01*
Y449802D01*
X162488Y449760D01*
X162474Y449691D01*
X162446Y449608D01*
X162418Y449497D01*
X162391Y449358D01*
X162349Y449206D01*
X162321Y449039D01*
X162280Y448845D01*
X162238Y448637D01*
X162169Y448193D01*
X162099Y447708D01*
X162058Y447181D01*
X160851D01*
Y447195D01*
Y447236D01*
Y447292D01*
X160865Y447375D01*
Y447486D01*
X160879Y447625D01*
X160893Y447777D01*
X160907Y447943D01*
X160935Y448138D01*
X160962Y448332D01*
X161004Y448568D01*
X161045Y448803D01*
X161087Y449053D01*
X161143Y449330D01*
X161281Y449899D01*
Y449913D01*
X161295Y449968D01*
X161323Y450051D01*
X161364Y450176D01*
X161406Y450315D01*
X161462Y450481D01*
X161517Y450676D01*
X161600Y450884D01*
X161684Y451119D01*
X161767Y451355D01*
X161975Y451882D01*
X162224Y452437D01*
X162502Y452992D01*
X162516Y453005D01*
X162543Y453061D01*
X162585Y453130D01*
X162640Y453241D01*
X162710Y453366D01*
X162807Y453519D01*
X162904Y453685D01*
X163015Y453865D01*
X163278Y454268D01*
X163556Y454683D01*
X163875Y455113D01*
X164207Y455516D01*
X159506D01*
Y456653D01*
X165719D01*
Y455724D01*
D02*
G37*
G36*
X155373Y456805D02*
X155484Y456791D01*
X155623Y456778D01*
X155775Y456750D01*
X155928Y456722D01*
X156289Y456625D01*
X156649Y456486D01*
X156830Y456403D01*
X157010Y456306D01*
X157176Y456181D01*
X157329Y456043D01*
X157343Y456029D01*
X157370Y456015D01*
X157398Y455959D01*
X157454Y455904D01*
X157523Y455835D01*
X157592Y455737D01*
X157662Y455640D01*
X157745Y455516D01*
X157884Y455252D01*
X158022Y454919D01*
X158078Y454753D01*
X158105Y454559D01*
X158133Y454365D01*
X158147Y454156D01*
Y454129D01*
Y454059D01*
X158133Y453949D01*
X158119Y453796D01*
X158092Y453629D01*
X158036Y453435D01*
X157981Y453227D01*
X157897Y453019D01*
X157884Y452992D01*
X157856Y452922D01*
X157800Y452811D01*
X157717Y452659D01*
X157606Y452492D01*
X157467Y452284D01*
X157301Y452076D01*
X157107Y451841D01*
X157079Y451813D01*
X157010Y451730D01*
X156940Y451660D01*
X156871Y451591D01*
X156788Y451508D01*
X156677Y451397D01*
X156566Y451286D01*
X156427Y451161D01*
X156289Y451022D01*
X156122Y450870D01*
X155942Y450717D01*
X155748Y450537D01*
X155526Y450357D01*
X155304Y450162D01*
X155290Y450149D01*
X155262Y450121D01*
X155207Y450079D01*
X155138Y450024D01*
X155054Y449941D01*
X154957Y449857D01*
X154735Y449677D01*
X154500Y449469D01*
X154278Y449261D01*
X154084Y449081D01*
X154000Y449011D01*
X153931Y448942D01*
X153917Y448928D01*
X153876Y448887D01*
X153820Y448831D01*
X153751Y448748D01*
X153681Y448651D01*
X153598Y448554D01*
X153432Y448318D01*
X158161D01*
Y447181D01*
X151795D01*
Y447195D01*
Y447250D01*
Y447333D01*
X151809Y447444D01*
X151823Y447569D01*
X151851Y447708D01*
X151878Y447846D01*
X151934Y447999D01*
Y448013D01*
X151948Y448027D01*
X151976Y448110D01*
X152031Y448235D01*
X152114Y448401D01*
X152225Y448595D01*
X152364Y448817D01*
X152516Y449039D01*
X152711Y449275D01*
Y449289D01*
X152738Y449303D01*
X152808Y449386D01*
X152933Y449511D01*
X153113Y449691D01*
X153321Y449899D01*
X153584Y450149D01*
X153903Y450426D01*
X154250Y450717D01*
X154264Y450731D01*
X154319Y450773D01*
X154403Y450842D01*
X154500Y450925D01*
X154625Y451036D01*
X154777Y451161D01*
X154930Y451300D01*
X155110Y451452D01*
X155457Y451785D01*
X155803Y452118D01*
X155970Y452284D01*
X156122Y452451D01*
X156261Y452603D01*
X156372Y452756D01*
Y452770D01*
X156400Y452784D01*
X156427Y452825D01*
X156455Y452881D01*
X156552Y453033D01*
X156663Y453214D01*
X156760Y453435D01*
X156857Y453671D01*
X156913Y453935D01*
X156940Y454184D01*
Y454198D01*
Y454212D01*
X156927Y454295D01*
X156913Y454434D01*
X156871Y454586D01*
X156816Y454781D01*
X156719Y454975D01*
X156594Y455169D01*
X156427Y455363D01*
X156400Y455391D01*
X156330Y455446D01*
X156233Y455516D01*
X156081Y455613D01*
X155886Y455696D01*
X155665Y455779D01*
X155401Y455835D01*
X155110Y455849D01*
X155027D01*
X154971Y455835D01*
X154805Y455821D01*
X154611Y455779D01*
X154403Y455724D01*
X154167Y455627D01*
X153945Y455502D01*
X153737Y455335D01*
X153709Y455308D01*
X153654Y455238D01*
X153570Y455127D01*
X153487Y454961D01*
X153390Y454767D01*
X153307Y454517D01*
X153251Y454240D01*
X153224Y453921D01*
X152017Y454046D01*
Y454059D01*
X152031Y454101D01*
Y454170D01*
X152045Y454268D01*
X152073Y454378D01*
X152100Y454503D01*
X152142Y454656D01*
X152184Y454808D01*
X152295Y455141D01*
X152461Y455474D01*
X152558Y455640D01*
X152683Y455807D01*
X152808Y455959D01*
X152946Y456098D01*
X152960Y456112D01*
X152988Y456126D01*
X153030Y456167D01*
X153099Y456209D01*
X153182Y456264D01*
X153279Y456320D01*
X153390Y456389D01*
X153529Y456459D01*
X153681Y456528D01*
X153848Y456597D01*
X154028Y456653D01*
X154222Y456708D01*
X154430Y456750D01*
X154652Y456791D01*
X154888Y456805D01*
X155138Y456819D01*
X155276D01*
X155373Y456805D01*
D02*
G37*
G36*
X147344Y456764D02*
X147468D01*
X147760Y456750D01*
X148065Y456708D01*
X148398Y456667D01*
X148703Y456597D01*
X148855Y456556D01*
X148980Y456514D01*
X148994D01*
X149008Y456500D01*
X149091Y456459D01*
X149216Y456403D01*
X149368Y456306D01*
X149535Y456181D01*
X149715Y456015D01*
X149881Y455821D01*
X150048Y455599D01*
Y455585D01*
X150062Y455571D01*
X150117Y455488D01*
X150173Y455349D01*
X150256Y455169D01*
X150325Y454961D01*
X150395Y454711D01*
X150436Y454448D01*
X150450Y454156D01*
Y454143D01*
Y454115D01*
Y454059D01*
X150436Y453990D01*
Y453893D01*
X150422Y453796D01*
X150367Y453560D01*
X150284Y453283D01*
X150173Y452992D01*
X150006Y452700D01*
X149895Y452562D01*
X149784Y452423D01*
X149770Y452409D01*
X149757Y452395D01*
X149715Y452354D01*
X149660Y452312D01*
X149590Y452257D01*
X149507Y452201D01*
X149396Y452132D01*
X149285Y452048D01*
X149146Y451979D01*
X148994Y451910D01*
X148827Y451827D01*
X148647Y451757D01*
X148439Y451702D01*
X148231Y451632D01*
X147995Y451591D01*
X147746Y451549D01*
X147774Y451535D01*
X147829Y451508D01*
X147912Y451452D01*
X148023Y451397D01*
X148273Y451244D01*
X148398Y451147D01*
X148509Y451064D01*
X148536Y451036D01*
X148606Y450967D01*
X148716Y450856D01*
X148855Y450717D01*
X149008Y450523D01*
X149188Y450315D01*
X149368Y450065D01*
X149563Y449788D01*
X151213Y447181D01*
X149632D01*
X148370Y449178D01*
Y449192D01*
X148342Y449219D01*
X148314Y449261D01*
X148273Y449316D01*
X148176Y449469D01*
X148051Y449663D01*
X147898Y449871D01*
X147746Y450093D01*
X147593Y450301D01*
X147455Y450495D01*
X147441Y450509D01*
X147399Y450565D01*
X147330Y450648D01*
X147233Y450745D01*
X147025Y450953D01*
X146914Y451050D01*
X146803Y451133D01*
X146789Y451147D01*
X146761Y451161D01*
X146706Y451189D01*
X146622Y451230D01*
X146539Y451272D01*
X146442Y451314D01*
X146220Y451383D01*
X146206D01*
X146179Y451397D01*
X146123D01*
X146054Y451411D01*
X145957Y451424D01*
X145846D01*
X145693Y451438D01*
X144057D01*
Y447181D01*
X142781D01*
Y456778D01*
X147233D01*
X147344Y456764D01*
D02*
G37*
G36*
X466532Y421425D02*
X466559Y421397D01*
X466615Y421342D01*
X466698Y421286D01*
X466795Y421203D01*
X466906Y421092D01*
X467045Y420981D01*
X467211Y420856D01*
X467378Y420731D01*
X467572Y420579D01*
X467794Y420426D01*
X468016Y420274D01*
X468265Y420107D01*
X468529Y419941D01*
X468820Y419774D01*
X469111Y419608D01*
X469125Y419594D01*
X469181Y419566D01*
X469264Y419525D01*
X469389Y419455D01*
X469541Y419386D01*
X469708Y419303D01*
X469902Y419206D01*
X470124Y419109D01*
X470373Y418998D01*
X470623Y418873D01*
X470900Y418762D01*
X471192Y418651D01*
X471788Y418429D01*
X472426Y418221D01*
X472440D01*
X472481Y418207D01*
X472551Y418193D01*
X472634Y418166D01*
X472745Y418138D01*
X472883Y418110D01*
X473036Y418069D01*
X473203Y418041D01*
X473397Y417999D01*
X473605Y417958D01*
X474049Y417888D01*
X474534Y417819D01*
X475061Y417777D01*
Y416571D01*
X475047D01*
X475005D01*
X474950D01*
X474867Y416585D01*
X474756D01*
X474617Y416599D01*
X474464Y416612D01*
X474298Y416626D01*
X474104Y416654D01*
X473910Y416682D01*
X473674Y416723D01*
X473438Y416765D01*
X473189Y416806D01*
X472911Y416862D01*
X472343Y417001D01*
X472329D01*
X472273Y417015D01*
X472190Y417042D01*
X472065Y417084D01*
X471927Y417126D01*
X471760Y417181D01*
X471566Y417236D01*
X471358Y417320D01*
X471122Y417403D01*
X470886Y417486D01*
X470359Y417694D01*
X469805Y417944D01*
X469250Y418221D01*
X469236Y418235D01*
X469181Y418263D01*
X469111Y418304D01*
X469000Y418360D01*
X468876Y418429D01*
X468723Y418526D01*
X468557Y418623D01*
X468376Y418734D01*
X467974Y418998D01*
X467558Y419275D01*
X467128Y419594D01*
X466726Y419927D01*
Y415225D01*
X465589D01*
Y421439D01*
X466518D01*
X466532Y421425D01*
D02*
G37*
G36*
X475061Y412812D02*
X473064Y411550D01*
X473050D01*
X473022Y411523D01*
X472981Y411495D01*
X472925Y411453D01*
X472773Y411356D01*
X472578Y411231D01*
X472370Y411079D01*
X472149Y410926D01*
X471940Y410774D01*
X471746Y410635D01*
X471732Y410621D01*
X471677Y410580D01*
X471594Y410510D01*
X471497Y410413D01*
X471289Y410205D01*
X471192Y410094D01*
X471108Y409983D01*
X471095Y409969D01*
X471081Y409942D01*
X471053Y409886D01*
X471011Y409803D01*
X470970Y409720D01*
X470928Y409623D01*
X470859Y409401D01*
Y409387D01*
X470845Y409359D01*
Y409304D01*
X470831Y409234D01*
X470817Y409137D01*
Y409026D01*
X470803Y408874D01*
Y407237D01*
X475061D01*
Y405961D01*
X465464D01*
Y410413D01*
X465478Y410524D01*
Y410649D01*
X465492Y410940D01*
X465533Y411245D01*
X465575Y411578D01*
X465644Y411883D01*
X465686Y412036D01*
X465727Y412161D01*
Y412174D01*
X465741Y412188D01*
X465783Y412271D01*
X465838Y412396D01*
X465935Y412549D01*
X466060Y412715D01*
X466227Y412896D01*
X466421Y413062D01*
X466643Y413228D01*
X466657D01*
X466670Y413242D01*
X466754Y413298D01*
X466892Y413353D01*
X467073Y413437D01*
X467281Y413506D01*
X467530Y413575D01*
X467794Y413617D01*
X468085Y413631D01*
X468099D01*
X468127D01*
X468182D01*
X468251Y413617D01*
X468349D01*
X468446Y413603D01*
X468681Y413547D01*
X468959Y413464D01*
X469250Y413353D01*
X469541Y413187D01*
X469680Y413076D01*
X469819Y412965D01*
X469832Y412951D01*
X469846Y412937D01*
X469888Y412896D01*
X469930Y412840D01*
X469985Y412771D01*
X470041Y412688D01*
X470110Y412577D01*
X470193Y412466D01*
X470262Y412327D01*
X470332Y412174D01*
X470415Y412008D01*
X470484Y411828D01*
X470540Y411620D01*
X470609Y411412D01*
X470651Y411176D01*
X470692Y410926D01*
X470706Y410954D01*
X470734Y411009D01*
X470789Y411093D01*
X470845Y411204D01*
X470997Y411453D01*
X471095Y411578D01*
X471178Y411689D01*
X471205Y411717D01*
X471275Y411786D01*
X471386Y411897D01*
X471524Y412036D01*
X471719Y412188D01*
X471927Y412369D01*
X472176Y412549D01*
X472454Y412743D01*
X475061Y414393D01*
Y412812D01*
D02*
G37*
G36*
X316140Y291245D02*
X316237D01*
X316348Y291231D01*
X316612Y291175D01*
X316903Y291106D01*
X317208Y290995D01*
X317513Y290828D01*
X317666Y290731D01*
X317804Y290620D01*
X317818Y290607D01*
X317832Y290593D01*
X317874Y290551D01*
X317915Y290509D01*
X317985Y290440D01*
X318040Y290357D01*
X318193Y290163D01*
X318345Y289913D01*
X318484Y289608D01*
X318609Y289261D01*
X318692Y288873D01*
X317513Y288776D01*
Y288790D01*
X317499Y288804D01*
X317485Y288887D01*
X317444Y289012D01*
X317388Y289164D01*
X317333Y289331D01*
X317250Y289497D01*
X317153Y289650D01*
X317055Y289774D01*
X317028Y289802D01*
X316972Y289858D01*
X316875Y289941D01*
X316737Y290038D01*
X316556Y290121D01*
X316362Y290204D01*
X316126Y290260D01*
X315877Y290288D01*
X315780D01*
X315669Y290274D01*
X315544Y290246D01*
X315377Y290204D01*
X315211Y290149D01*
X315044Y290080D01*
X314878Y289969D01*
X314850Y289955D01*
X314781Y289899D01*
X314684Y289802D01*
X314559Y289664D01*
X314421Y289497D01*
X314268Y289303D01*
X314129Y289053D01*
X313990Y288776D01*
Y288762D01*
X313977Y288734D01*
X313963Y288693D01*
X313935Y288637D01*
X313921Y288554D01*
X313894Y288457D01*
X313866Y288346D01*
X313838Y288207D01*
X313796Y288055D01*
X313769Y287888D01*
X313741Y287708D01*
X313727Y287514D01*
X313699Y287292D01*
X313685Y287070D01*
X313672Y286821D01*
Y286571D01*
X313685Y286585D01*
X313741Y286668D01*
X313838Y286779D01*
X313963Y286918D01*
X314102Y287084D01*
X314282Y287237D01*
X314476Y287389D01*
X314698Y287528D01*
X314712D01*
X314726Y287542D01*
X314809Y287583D01*
X314934Y287625D01*
X315100Y287694D01*
X315294Y287750D01*
X315516Y287791D01*
X315752Y287833D01*
X316001Y287847D01*
X316112D01*
X316196Y287833D01*
X316307Y287819D01*
X316418Y287805D01*
X316556Y287777D01*
X316695Y287736D01*
X317014Y287639D01*
X317180Y287569D01*
X317347Y287472D01*
X317513Y287375D01*
X317693Y287264D01*
X317860Y287126D01*
X318012Y286973D01*
X318026Y286959D01*
X318054Y286931D01*
X318096Y286890D01*
X318137Y286821D01*
X318207Y286723D01*
X318276Y286626D01*
X318345Y286502D01*
X318428Y286363D01*
X318512Y286210D01*
X318581Y286044D01*
X318650Y285850D01*
X318720Y285656D01*
X318761Y285448D01*
X318803Y285212D01*
X318831Y284976D01*
X318845Y284726D01*
Y284713D01*
Y284685D01*
Y284643D01*
Y284574D01*
X318831Y284491D01*
Y284407D01*
X318789Y284186D01*
X318747Y283922D01*
X318678Y283645D01*
X318581Y283340D01*
X318442Y283048D01*
Y283034D01*
X318428Y283021D01*
X318401Y282979D01*
X318373Y282924D01*
X318290Y282785D01*
X318165Y282605D01*
X318012Y282410D01*
X317832Y282216D01*
X317610Y282022D01*
X317374Y281856D01*
X317361D01*
X317347Y281842D01*
X317305Y281814D01*
X317250Y281800D01*
X317111Y281731D01*
X316931Y281661D01*
X316695Y281578D01*
X316431Y281523D01*
X316140Y281467D01*
X315821Y281453D01*
X315752D01*
X315683Y281467D01*
X315571D01*
X315447Y281481D01*
X315308Y281509D01*
X315142Y281551D01*
X314975Y281592D01*
X314781Y281648D01*
X314587Y281717D01*
X314393Y281800D01*
X314185Y281911D01*
X313990Y282036D01*
X313796Y282175D01*
X313602Y282341D01*
X313422Y282535D01*
X313408Y282549D01*
X313380Y282591D01*
X313339Y282646D01*
X313283Y282743D01*
X313200Y282868D01*
X313131Y283007D01*
X313048Y283187D01*
X312964Y283381D01*
X312867Y283617D01*
X312784Y283880D01*
X312715Y284172D01*
X312645Y284491D01*
X312576Y284851D01*
X312534Y285240D01*
X312507Y285656D01*
X312493Y286099D01*
Y286113D01*
Y286127D01*
Y286169D01*
Y286224D01*
X312507Y286363D01*
Y286557D01*
X312521Y286779D01*
X312548Y287042D01*
X312576Y287334D01*
X312618Y287653D01*
X312673Y287972D01*
X312742Y288318D01*
X312826Y288651D01*
X312923Y288984D01*
X313048Y289303D01*
X313186Y289608D01*
X313339Y289899D01*
X313519Y290149D01*
X313533Y290163D01*
X313561Y290191D01*
X313616Y290246D01*
X313685Y290329D01*
X313769Y290412D01*
X313880Y290496D01*
X314018Y290607D01*
X314157Y290704D01*
X314323Y290801D01*
X314504Y290912D01*
X314712Y290995D01*
X314920Y291092D01*
X315156Y291161D01*
X315405Y291217D01*
X315669Y291245D01*
X315946Y291258D01*
X316057D01*
X316140Y291245D01*
D02*
G37*
G36*
X307930Y291203D02*
X308055D01*
X308346Y291189D01*
X308651Y291147D01*
X308984Y291106D01*
X309289Y291036D01*
X309442Y290995D01*
X309566Y290953D01*
X309580D01*
X309594Y290939D01*
X309678Y290898D01*
X309802Y290842D01*
X309955Y290745D01*
X310121Y290620D01*
X310301Y290454D01*
X310468Y290260D01*
X310634Y290038D01*
Y290024D01*
X310648Y290010D01*
X310704Y289927D01*
X310759Y289788D01*
X310842Y289608D01*
X310912Y289400D01*
X310981Y289150D01*
X311023Y288887D01*
X311037Y288596D01*
Y288582D01*
Y288554D01*
Y288499D01*
X311023Y288429D01*
Y288332D01*
X311009Y288235D01*
X310953Y287999D01*
X310870Y287722D01*
X310759Y287431D01*
X310593Y287139D01*
X310482Y287001D01*
X310371Y286862D01*
X310357Y286848D01*
X310343Y286834D01*
X310301Y286793D01*
X310246Y286751D01*
X310177Y286696D01*
X310093Y286640D01*
X309983Y286571D01*
X309872Y286488D01*
X309733Y286418D01*
X309580Y286349D01*
X309414Y286266D01*
X309234Y286196D01*
X309026Y286141D01*
X308818Y286072D01*
X308582Y286030D01*
X308332Y285988D01*
X308360Y285975D01*
X308415Y285947D01*
X308499Y285891D01*
X308610Y285836D01*
X308859Y285683D01*
X308984Y285586D01*
X309095Y285503D01*
X309123Y285475D01*
X309192Y285406D01*
X309303Y285295D01*
X309442Y285156D01*
X309594Y284962D01*
X309774Y284754D01*
X309955Y284505D01*
X310149Y284227D01*
X311799Y281620D01*
X310218D01*
X308956Y283617D01*
Y283631D01*
X308929Y283659D01*
X308901Y283700D01*
X308859Y283756D01*
X308762Y283908D01*
X308637Y284102D01*
X308485Y284310D01*
X308332Y284532D01*
X308180Y284740D01*
X308041Y284934D01*
X308027Y284948D01*
X307985Y285004D01*
X307916Y285087D01*
X307819Y285184D01*
X307611Y285392D01*
X307500Y285489D01*
X307389Y285572D01*
X307375Y285586D01*
X307348Y285600D01*
X307292Y285628D01*
X307209Y285669D01*
X307126Y285711D01*
X307029Y285753D01*
X306807Y285822D01*
X306793D01*
X306765Y285836D01*
X306710D01*
X306640Y285850D01*
X306543Y285864D01*
X306432D01*
X306280Y285877D01*
X304643D01*
Y281620D01*
X303367D01*
Y291217D01*
X307819D01*
X307930Y291203D01*
D02*
G37*
G36*
X368927Y230692D02*
Y226628D01*
X367651D01*
Y230692D01*
X363948Y236225D01*
X365488D01*
X367374Y233313D01*
Y233299D01*
X367401Y233271D01*
X367429Y233230D01*
X367457Y233174D01*
X367512Y233105D01*
X367568Y233022D01*
X367693Y232813D01*
X367845Y232564D01*
X368012Y232286D01*
X368192Y231995D01*
X368358Y231690D01*
Y231704D01*
X368372Y231732D01*
X368400Y231773D01*
X368442Y231829D01*
X368483Y231898D01*
X368539Y231981D01*
X368663Y232189D01*
X368816Y232439D01*
X368996Y232730D01*
X369204Y233049D01*
X369426Y233396D01*
X371271Y236225D01*
X372755D01*
X368927Y230692D01*
D02*
G37*
G36*
X378371Y230012D02*
X379675D01*
Y228930D01*
X378371D01*
Y226628D01*
X377192D01*
Y228930D01*
X373018D01*
Y230012D01*
X377414Y236225D01*
X378371D01*
Y230012D01*
D02*
G37*
G36*
X346917Y211094D02*
X347042Y211080D01*
X347195Y211067D01*
X347347Y211053D01*
X347527Y211011D01*
X347902Y210928D01*
X348318Y210803D01*
X348526Y210720D01*
X348720Y210623D01*
X348914Y210498D01*
X349108Y210373D01*
X349122Y210359D01*
X349150Y210345D01*
X349205Y210304D01*
X349275Y210235D01*
X349344Y210165D01*
X349441Y210068D01*
X349538Y209957D01*
X349649Y209846D01*
X349760Y209708D01*
X349871Y209541D01*
X349996Y209375D01*
X350107Y209194D01*
X350204Y208986D01*
X350315Y208778D01*
X350398Y208556D01*
X350481Y208307D01*
X349233Y208015D01*
Y208029D01*
X349219Y208057D01*
X349192Y208113D01*
X349164Y208182D01*
X349136Y208265D01*
X349094Y208376D01*
X348983Y208598D01*
X348845Y208848D01*
X348678Y209097D01*
X348470Y209333D01*
X348248Y209541D01*
X348221Y209569D01*
X348138Y209624D01*
X347999Y209694D01*
X347818Y209791D01*
X347583Y209874D01*
X347319Y209957D01*
X347000Y210013D01*
X346654Y210026D01*
X346543D01*
X346473Y210013D01*
X346376D01*
X346265Y209999D01*
X346002Y209957D01*
X345710Y209902D01*
X345405Y209805D01*
X345087Y209666D01*
X344795Y209486D01*
X344781D01*
X344767Y209458D01*
X344670Y209389D01*
X344546Y209278D01*
X344393Y209111D01*
X344213Y208903D01*
X344046Y208667D01*
X343894Y208376D01*
X343755Y208057D01*
Y208043D01*
X343741Y208015D01*
X343727Y207974D01*
X343713Y207905D01*
X343686Y207821D01*
X343658Y207724D01*
X343616Y207488D01*
X343561Y207211D01*
X343506Y206906D01*
X343478Y206573D01*
X343464Y206213D01*
Y206199D01*
Y206157D01*
Y206088D01*
Y206005D01*
X343478Y205907D01*
Y205783D01*
X343492Y205644D01*
X343506Y205492D01*
X343547Y205159D01*
X343616Y204798D01*
X343700Y204438D01*
X343811Y204077D01*
Y204063D01*
X343824Y204035D01*
X343852Y203994D01*
X343880Y203924D01*
X343963Y203758D01*
X344088Y203564D01*
X344240Y203342D01*
X344435Y203106D01*
X344656Y202898D01*
X344920Y202704D01*
X344934D01*
X344962Y202690D01*
X345003Y202662D01*
X345059Y202635D01*
X345128Y202607D01*
X345211Y202565D01*
X345405Y202482D01*
X345655Y202399D01*
X345932Y202330D01*
X346237Y202274D01*
X346557Y202260D01*
X346654D01*
X346737Y202274D01*
X346834D01*
X346931Y202288D01*
X347181Y202343D01*
X347472Y202413D01*
X347763Y202524D01*
X348068Y202676D01*
X348221Y202759D01*
X348359Y202870D01*
X348373Y202884D01*
X348387Y202898D01*
X348429Y202940D01*
X348484Y202981D01*
X348540Y203051D01*
X348609Y203134D01*
X348692Y203217D01*
X348762Y203328D01*
X348845Y203453D01*
X348942Y203591D01*
X349025Y203730D01*
X349108Y203897D01*
X349178Y204077D01*
X349247Y204271D01*
X349316Y204479D01*
X349372Y204701D01*
X350648Y204382D01*
Y204368D01*
X350634Y204313D01*
X350606Y204230D01*
X350564Y204118D01*
X350523Y203994D01*
X350467Y203841D01*
X350398Y203675D01*
X350315Y203494D01*
X350121Y203106D01*
X349871Y202718D01*
X349719Y202524D01*
X349566Y202330D01*
X349399Y202163D01*
X349205Y201997D01*
X349192Y201983D01*
X349164Y201955D01*
X349094Y201927D01*
X349025Y201872D01*
X348914Y201803D01*
X348803Y201733D01*
X348651Y201664D01*
X348498Y201595D01*
X348318Y201511D01*
X348124Y201442D01*
X347916Y201373D01*
X347694Y201303D01*
X347458Y201248D01*
X347208Y201220D01*
X346945Y201192D01*
X346668Y201178D01*
X346515D01*
X346404Y201192D01*
X346279D01*
X346127Y201206D01*
X345960Y201234D01*
X345766Y201262D01*
X345364Y201331D01*
X344948Y201442D01*
X344532Y201595D01*
X344338Y201691D01*
X344143Y201803D01*
X344129Y201816D01*
X344102Y201830D01*
X344046Y201872D01*
X343991Y201927D01*
X343908Y201983D01*
X343811Y202066D01*
X343700Y202163D01*
X343589Y202274D01*
X343478Y202399D01*
X343353Y202524D01*
X343103Y202843D01*
X342868Y203217D01*
X342659Y203633D01*
Y203647D01*
X342632Y203689D01*
X342618Y203758D01*
X342576Y203841D01*
X342548Y203952D01*
X342507Y204091D01*
X342452Y204243D01*
X342410Y204410D01*
X342368Y204590D01*
X342313Y204798D01*
X342243Y205228D01*
X342188Y205713D01*
X342160Y206213D01*
Y206227D01*
Y206282D01*
Y206365D01*
X342174Y206462D01*
Y206601D01*
X342188Y206740D01*
X342202Y206920D01*
X342230Y207100D01*
X342299Y207502D01*
X342396Y207946D01*
X342535Y208390D01*
X342729Y208820D01*
X342743Y208834D01*
X342757Y208875D01*
X342784Y208931D01*
X342840Y209000D01*
X342895Y209097D01*
X342965Y209208D01*
X343145Y209458D01*
X343381Y209735D01*
X343658Y210013D01*
X343977Y210290D01*
X344351Y210526D01*
X344365Y210540D01*
X344407Y210553D01*
X344462Y210581D01*
X344532Y210623D01*
X344643Y210664D01*
X344754Y210706D01*
X344892Y210762D01*
X345045Y210817D01*
X345211Y210872D01*
X345392Y210928D01*
X345780Y211011D01*
X346224Y211080D01*
X346681Y211108D01*
X346820D01*
X346917Y211094D01*
D02*
G37*
G36*
X355141Y210970D02*
X355252Y210956D01*
X355391Y210942D01*
X355543Y210914D01*
X355696Y210886D01*
X356056Y210789D01*
X356417Y210651D01*
X356597Y210567D01*
X356777Y210470D01*
X356944Y210345D01*
X357096Y210207D01*
X357110Y210193D01*
X357138Y210179D01*
X357166Y210124D01*
X357221Y210068D01*
X357291Y209999D01*
X357360Y209902D01*
X357429Y209805D01*
X357513Y209680D01*
X357651Y209416D01*
X357790Y209083D01*
X357845Y208917D01*
X357873Y208723D01*
X357901Y208529D01*
X357915Y208321D01*
Y208293D01*
Y208224D01*
X357901Y208113D01*
X357887Y207960D01*
X357859Y207794D01*
X357804Y207600D01*
X357748Y207391D01*
X357665Y207183D01*
X357651Y207156D01*
X357623Y207086D01*
X357568Y206975D01*
X357485Y206823D01*
X357374Y206656D01*
X357235Y206448D01*
X357069Y206240D01*
X356875Y206005D01*
X356847Y205977D01*
X356777Y205894D01*
X356708Y205824D01*
X356639Y205755D01*
X356556Y205672D01*
X356445Y205561D01*
X356334Y205450D01*
X356195Y205325D01*
X356056Y205186D01*
X355890Y205034D01*
X355710Y204881D01*
X355516Y204701D01*
X355294Y204521D01*
X355072Y204326D01*
X355058Y204313D01*
X355030Y204285D01*
X354975Y204243D01*
X354905Y204188D01*
X354822Y204105D01*
X354725Y204021D01*
X354503Y203841D01*
X354267Y203633D01*
X354045Y203425D01*
X353851Y203245D01*
X353768Y203176D01*
X353699Y203106D01*
X353685Y203092D01*
X353643Y203051D01*
X353588Y202995D01*
X353518Y202912D01*
X353449Y202815D01*
X353366Y202718D01*
X353200Y202482D01*
X357929D01*
Y201345D01*
X351563D01*
Y201359D01*
Y201414D01*
Y201497D01*
X351577Y201608D01*
X351591Y201733D01*
X351618Y201872D01*
X351646Y202010D01*
X351702Y202163D01*
Y202177D01*
X351716Y202191D01*
X351743Y202274D01*
X351799Y202399D01*
X351882Y202565D01*
X351993Y202759D01*
X352132Y202981D01*
X352284Y203203D01*
X352478Y203439D01*
Y203453D01*
X352506Y203467D01*
X352575Y203550D01*
X352700Y203675D01*
X352881Y203855D01*
X353088Y204063D01*
X353352Y204313D01*
X353671Y204590D01*
X354018Y204881D01*
X354032Y204895D01*
X354087Y204937D01*
X354170Y205006D01*
X354267Y205089D01*
X354392Y205200D01*
X354545Y205325D01*
X354697Y205464D01*
X354878Y205616D01*
X355224Y205949D01*
X355571Y206282D01*
X355737Y206448D01*
X355890Y206615D01*
X356029Y206767D01*
X356140Y206920D01*
Y206934D01*
X356167Y206948D01*
X356195Y206989D01*
X356223Y207045D01*
X356320Y207197D01*
X356431Y207378D01*
X356528Y207600D01*
X356625Y207835D01*
X356680Y208099D01*
X356708Y208348D01*
Y208362D01*
Y208376D01*
X356694Y208459D01*
X356680Y208598D01*
X356639Y208751D01*
X356583Y208945D01*
X356486Y209139D01*
X356362Y209333D01*
X356195Y209527D01*
X356167Y209555D01*
X356098Y209610D01*
X356001Y209680D01*
X355848Y209777D01*
X355654Y209860D01*
X355432Y209943D01*
X355169Y209999D01*
X354878Y210013D01*
X354794D01*
X354739Y209999D01*
X354572Y209985D01*
X354378Y209943D01*
X354170Y209888D01*
X353935Y209791D01*
X353713Y209666D01*
X353505Y209499D01*
X353477Y209472D01*
X353421Y209402D01*
X353338Y209291D01*
X353255Y209125D01*
X353158Y208931D01*
X353075Y208681D01*
X353019Y208404D01*
X352991Y208085D01*
X351785Y208210D01*
Y208224D01*
X351799Y208265D01*
Y208335D01*
X351813Y208432D01*
X351840Y208542D01*
X351868Y208667D01*
X351910Y208820D01*
X351951Y208972D01*
X352062Y209305D01*
X352229Y209638D01*
X352326Y209805D01*
X352451Y209971D01*
X352575Y210124D01*
X352714Y210262D01*
X352728Y210276D01*
X352756Y210290D01*
X352797Y210332D01*
X352867Y210373D01*
X352950Y210429D01*
X353047Y210484D01*
X353158Y210553D01*
X353297Y210623D01*
X353449Y210692D01*
X353615Y210762D01*
X353796Y210817D01*
X353990Y210872D01*
X354198Y210914D01*
X354420Y210956D01*
X354656Y210970D01*
X354905Y210983D01*
X355044D01*
X355141Y210970D01*
D02*
G37*
G36*
X362602D02*
X362783Y210942D01*
X362991Y210900D01*
X363213Y210845D01*
X363448Y210775D01*
X363670Y210664D01*
X363684D01*
X363698Y210651D01*
X363767Y210609D01*
X363878Y210540D01*
X364017Y210443D01*
X364169Y210304D01*
X364336Y210151D01*
X364488Y209971D01*
X364641Y209763D01*
X364655Y209735D01*
X364710Y209666D01*
X364766Y209541D01*
X364863Y209361D01*
X364946Y209153D01*
X365057Y208917D01*
X365154Y208640D01*
X365237Y208335D01*
Y208321D01*
X365251Y208293D01*
X365265Y208251D01*
X365279Y208182D01*
X365293Y208099D01*
X365307Y208002D01*
X365334Y207877D01*
X365348Y207738D01*
X365376Y207586D01*
X365390Y207419D01*
X365404Y207225D01*
X365431Y207031D01*
X365445Y206809D01*
Y206587D01*
X365459Y206338D01*
Y206074D01*
Y206060D01*
Y206005D01*
Y205907D01*
Y205797D01*
X365445Y205644D01*
Y205478D01*
X365431Y205297D01*
X365418Y205103D01*
X365376Y204659D01*
X365307Y204202D01*
X365223Y203758D01*
X365168Y203550D01*
X365099Y203342D01*
Y203328D01*
X365085Y203300D01*
X365057Y203245D01*
X365029Y203176D01*
X365001Y203078D01*
X364946Y202981D01*
X364835Y202745D01*
X364696Y202496D01*
X364516Y202218D01*
X364308Y201969D01*
X364058Y201733D01*
X364045D01*
X364031Y201705D01*
X363989Y201678D01*
X363934Y201650D01*
X363864Y201608D01*
X363795Y201553D01*
X363587Y201456D01*
X363337Y201359D01*
X363046Y201262D01*
X362699Y201206D01*
X362325Y201178D01*
X362186D01*
X362089Y201192D01*
X361978Y201206D01*
X361839Y201234D01*
X361687Y201262D01*
X361521Y201303D01*
X361354Y201359D01*
X361174Y201414D01*
X360993Y201497D01*
X360813Y201595D01*
X360633Y201705D01*
X360453Y201844D01*
X360286Y201997D01*
X360134Y202163D01*
X360120Y202177D01*
X360092Y202218D01*
X360051Y202288D01*
X359981Y202399D01*
X359912Y202524D01*
X359842Y202690D01*
X359745Y202884D01*
X359662Y203106D01*
X359579Y203356D01*
X359496Y203647D01*
X359412Y203966D01*
X359343Y204326D01*
X359274Y204715D01*
X359232Y205131D01*
X359204Y205589D01*
X359191Y206074D01*
Y206088D01*
Y206143D01*
Y206240D01*
Y206351D01*
X359204Y206504D01*
Y206670D01*
X359218Y206851D01*
X359232Y207059D01*
X359274Y207488D01*
X359343Y207946D01*
X359426Y208404D01*
X359482Y208612D01*
X359537Y208820D01*
Y208834D01*
X359551Y208862D01*
X359579Y208917D01*
X359607Y208986D01*
X359634Y209083D01*
X359690Y209181D01*
X359801Y209416D01*
X359939Y209666D01*
X360120Y209929D01*
X360328Y210193D01*
X360578Y210415D01*
X360591D01*
X360605Y210443D01*
X360647Y210470D01*
X360702Y210498D01*
X360772Y210553D01*
X360855Y210595D01*
X361063Y210706D01*
X361312Y210803D01*
X361604Y210900D01*
X361950Y210956D01*
X362325Y210983D01*
X362450D01*
X362602Y210970D01*
D02*
G37*
G36*
X346896Y222896D02*
X347021Y222882D01*
X347174Y222868D01*
X347326Y222854D01*
X347506Y222812D01*
X347881Y222729D01*
X348297Y222605D01*
X348505Y222521D01*
X348699Y222424D01*
X348893Y222299D01*
X349087Y222175D01*
X349101Y222161D01*
X349129Y222147D01*
X349185Y222105D01*
X349254Y222036D01*
X349323Y221967D01*
X349420Y221870D01*
X349517Y221758D01*
X349628Y221648D01*
X349739Y221509D01*
X349850Y221343D01*
X349975Y221176D01*
X350086Y220996D01*
X350183Y220788D01*
X350294Y220580D01*
X350377Y220358D01*
X350461Y220108D01*
X349212Y219817D01*
Y219831D01*
X349198Y219859D01*
X349171Y219914D01*
X349143Y219983D01*
X349115Y220067D01*
X349074Y220177D01*
X348963Y220399D01*
X348824Y220649D01*
X348658Y220899D01*
X348450Y221134D01*
X348228Y221343D01*
X348200Y221370D01*
X348117Y221426D01*
X347978Y221495D01*
X347798Y221592D01*
X347562Y221675D01*
X347299Y221758D01*
X346979Y221814D01*
X346633Y221828D01*
X346522D01*
X346452Y221814D01*
X346355D01*
X346245Y221800D01*
X345981Y221758D01*
X345690Y221703D01*
X345385Y221606D01*
X345066Y221467D01*
X344774Y221287D01*
X344761D01*
X344747Y221259D01*
X344650Y221190D01*
X344525Y221079D01*
X344372Y220913D01*
X344192Y220704D01*
X344025Y220469D01*
X343873Y220177D01*
X343734Y219859D01*
Y219845D01*
X343720Y219817D01*
X343707Y219775D01*
X343693Y219706D01*
X343665Y219623D01*
X343637Y219526D01*
X343596Y219290D01*
X343540Y219013D01*
X343485Y218708D01*
X343457Y218375D01*
X343443Y218014D01*
Y218000D01*
Y217959D01*
Y217889D01*
Y217806D01*
X343457Y217709D01*
Y217584D01*
X343471Y217446D01*
X343485Y217293D01*
X343526Y216960D01*
X343596Y216600D01*
X343679Y216239D01*
X343790Y215878D01*
Y215865D01*
X343804Y215837D01*
X343831Y215795D01*
X343859Y215726D01*
X343942Y215559D01*
X344067Y215365D01*
X344220Y215143D01*
X344414Y214907D01*
X344636Y214699D01*
X344899Y214505D01*
X344913D01*
X344941Y214492D01*
X344982Y214464D01*
X345038Y214436D01*
X345107Y214408D01*
X345191Y214367D01*
X345385Y214284D01*
X345634Y214200D01*
X345912Y214131D01*
X346217Y214075D01*
X346536Y214062D01*
X346633D01*
X346716Y214075D01*
X346813D01*
X346910Y214089D01*
X347160Y214145D01*
X347451Y214214D01*
X347742Y214325D01*
X348047Y214478D01*
X348200Y214561D01*
X348339Y214672D01*
X348353Y214686D01*
X348366Y214699D01*
X348408Y214741D01*
X348463Y214783D01*
X348519Y214852D01*
X348588Y214935D01*
X348671Y215019D01*
X348741Y215129D01*
X348824Y215254D01*
X348921Y215393D01*
X349004Y215532D01*
X349087Y215698D01*
X349157Y215878D01*
X349226Y216073D01*
X349296Y216280D01*
X349351Y216502D01*
X350627Y216183D01*
Y216170D01*
X350613Y216114D01*
X350585Y216031D01*
X350544Y215920D01*
X350502Y215795D01*
X350447Y215643D01*
X350377Y215476D01*
X350294Y215296D01*
X350100Y214907D01*
X349850Y214519D01*
X349698Y214325D01*
X349545Y214131D01*
X349379Y213965D01*
X349185Y213798D01*
X349171Y213784D01*
X349143Y213757D01*
X349074Y213729D01*
X349004Y213673D01*
X348893Y213604D01*
X348782Y213535D01*
X348630Y213465D01*
X348477Y213396D01*
X348297Y213313D01*
X348103Y213243D01*
X347895Y213174D01*
X347673Y213105D01*
X347437Y213049D01*
X347188Y213021D01*
X346924Y212994D01*
X346647Y212980D01*
X346494D01*
X346383Y212994D01*
X346258D01*
X346106Y213008D01*
X345939Y213035D01*
X345745Y213063D01*
X345343Y213132D01*
X344927Y213243D01*
X344511Y213396D01*
X344317Y213493D01*
X344123Y213604D01*
X344109Y213618D01*
X344081Y213632D01*
X344025Y213673D01*
X343970Y213729D01*
X343887Y213784D01*
X343790Y213867D01*
X343679Y213965D01*
X343568Y214075D01*
X343457Y214200D01*
X343332Y214325D01*
X343083Y214644D01*
X342847Y215019D01*
X342639Y215434D01*
Y215448D01*
X342611Y215490D01*
X342597Y215559D01*
X342556Y215643D01*
X342528Y215753D01*
X342486Y215892D01*
X342431Y216045D01*
X342389Y216211D01*
X342347Y216392D01*
X342292Y216600D01*
X342223Y217029D01*
X342167Y217515D01*
X342139Y218014D01*
Y218028D01*
Y218083D01*
Y218167D01*
X342153Y218264D01*
Y218402D01*
X342167Y218541D01*
X342181Y218721D01*
X342209Y218902D01*
X342278Y219304D01*
X342375Y219748D01*
X342514Y220191D01*
X342708Y220621D01*
X342722Y220635D01*
X342736Y220677D01*
X342763Y220732D01*
X342819Y220802D01*
X342874Y220899D01*
X342944Y221010D01*
X343124Y221259D01*
X343360Y221537D01*
X343637Y221814D01*
X343956Y222091D01*
X344331Y222327D01*
X344344Y222341D01*
X344386Y222355D01*
X344442Y222383D01*
X344511Y222424D01*
X344622Y222466D01*
X344733Y222507D01*
X344871Y222563D01*
X345024Y222618D01*
X345191Y222674D01*
X345371Y222729D01*
X345759Y222812D01*
X346203Y222882D01*
X346660Y222910D01*
X346799D01*
X346896Y222896D01*
D02*
G37*
G36*
X362346Y222771D02*
X362415D01*
X362512Y222757D01*
X362748Y222715D01*
X363011Y222660D01*
X363303Y222563D01*
X363594Y222438D01*
X363885Y222272D01*
X363899D01*
X363913Y222244D01*
X363954Y222216D01*
X364010Y222175D01*
X364149Y222064D01*
X364329Y221911D01*
X364509Y221703D01*
X364717Y221453D01*
X364897Y221162D01*
X365064Y220829D01*
Y220816D01*
X365078Y220788D01*
X365106Y220732D01*
X365133Y220663D01*
X365161Y220566D01*
X365203Y220441D01*
X365230Y220302D01*
X365272Y220150D01*
X365313Y219970D01*
X365355Y219762D01*
X365383Y219540D01*
X365411Y219304D01*
X365438Y219040D01*
X365466Y218763D01*
X365480Y218458D01*
Y218139D01*
Y218125D01*
Y218056D01*
Y217959D01*
Y217834D01*
X365466Y217681D01*
Y217501D01*
X365452Y217293D01*
X365424Y217085D01*
X365383Y216613D01*
X365313Y216114D01*
X365216Y215643D01*
X365147Y215407D01*
X365078Y215199D01*
Y215185D01*
X365064Y215157D01*
X365036Y215102D01*
X365008Y215019D01*
X364967Y214935D01*
X364911Y214824D01*
X364773Y214589D01*
X364606Y214325D01*
X364412Y214048D01*
X364162Y213784D01*
X363885Y213548D01*
X363871D01*
X363843Y213521D01*
X363802Y213493D01*
X363746Y213465D01*
X363663Y213424D01*
X363580Y213368D01*
X363469Y213313D01*
X363358Y213271D01*
X363095Y213160D01*
X362776Y213063D01*
X362429Y213008D01*
X362041Y212980D01*
X361930D01*
X361860Y212994D01*
X361763D01*
X361652Y213008D01*
X361389Y213063D01*
X361097Y213132D01*
X360792Y213243D01*
X360487Y213396D01*
X360335Y213493D01*
X360196Y213604D01*
X360182Y213618D01*
X360168Y213632D01*
X360127Y213673D01*
X360085Y213715D01*
X360030Y213784D01*
X359960Y213867D01*
X359822Y214062D01*
X359683Y214311D01*
X359544Y214616D01*
X359433Y214963D01*
X359350Y215365D01*
X360487Y215462D01*
Y215448D01*
X360501Y215421D01*
Y215393D01*
X360515Y215338D01*
X360557Y215185D01*
X360612Y215019D01*
X360681Y214824D01*
X360779Y214630D01*
X360890Y214450D01*
X361028Y214297D01*
X361042Y214284D01*
X361097Y214242D01*
X361195Y214186D01*
X361306Y214131D01*
X361458Y214062D01*
X361638Y214006D01*
X361846Y213965D01*
X362068Y213951D01*
X362165D01*
X362262Y213965D01*
X362387Y213978D01*
X362540Y214006D01*
X362692Y214048D01*
X362859Y214103D01*
X363011Y214186D01*
X363025Y214200D01*
X363081Y214228D01*
X363164Y214284D01*
X363247Y214367D01*
X363358Y214464D01*
X363469Y214575D01*
X363580Y214699D01*
X363691Y214852D01*
X363705Y214866D01*
X363732Y214935D01*
X363788Y215032D01*
X363843Y215157D01*
X363913Y215324D01*
X363982Y215518D01*
X364052Y215740D01*
X364121Y215989D01*
Y216003D01*
X364135Y216017D01*
Y216059D01*
X364149Y216114D01*
X364176Y216253D01*
X364218Y216433D01*
X364246Y216655D01*
X364273Y216891D01*
X364287Y217154D01*
X364301Y217432D01*
Y217446D01*
Y217487D01*
Y217556D01*
Y217667D01*
X364287Y217640D01*
X364232Y217570D01*
X364149Y217473D01*
X364052Y217334D01*
X363913Y217196D01*
X363746Y217043D01*
X363552Y216891D01*
X363330Y216752D01*
X363303Y216738D01*
X363219Y216697D01*
X363095Y216641D01*
X362942Y216586D01*
X362734Y216516D01*
X362512Y216461D01*
X362262Y216419D01*
X361999Y216405D01*
X361888D01*
X361805Y216419D01*
X361694Y216433D01*
X361583Y216447D01*
X361444Y216475D01*
X361306Y216516D01*
X360987Y216613D01*
X360820Y216683D01*
X360654Y216766D01*
X360473Y216863D01*
X360307Y216988D01*
X360141Y217113D01*
X359988Y217265D01*
X359974Y217279D01*
X359946Y217307D01*
X359919Y217348D01*
X359863Y217418D01*
X359794Y217515D01*
X359725Y217612D01*
X359655Y217737D01*
X359586Y217875D01*
X359503Y218028D01*
X359433Y218194D01*
X359364Y218389D01*
X359295Y218583D01*
X359239Y218805D01*
X359211Y219040D01*
X359184Y219276D01*
X359170Y219540D01*
Y219554D01*
Y219609D01*
Y219678D01*
X359184Y219775D01*
X359198Y219900D01*
X359211Y220053D01*
X359239Y220205D01*
X359281Y220386D01*
X359378Y220746D01*
X359447Y220940D01*
X359530Y221148D01*
X359627Y221343D01*
X359752Y221523D01*
X359877Y221717D01*
X360030Y221883D01*
X360043Y221897D01*
X360071Y221925D01*
X360113Y221967D01*
X360182Y222022D01*
X360265Y222091D01*
X360376Y222175D01*
X360487Y222244D01*
X360626Y222341D01*
X360765Y222424D01*
X360931Y222494D01*
X361306Y222646D01*
X361500Y222702D01*
X361722Y222743D01*
X361944Y222771D01*
X362179Y222785D01*
X362276D01*
X362346Y222771D01*
D02*
G37*
G36*
X356147Y213146D02*
X354968D01*
Y220649D01*
X354954Y220635D01*
X354884Y220580D01*
X354801Y220497D01*
X354663Y220399D01*
X354510Y220275D01*
X354316Y220136D01*
X354094Y219983D01*
X353844Y219831D01*
X353830D01*
X353817Y219817D01*
X353733Y219762D01*
X353595Y219692D01*
X353428Y219609D01*
X353234Y219512D01*
X353026Y219415D01*
X352818Y219318D01*
X352610Y219235D01*
Y220372D01*
X352624D01*
X352652Y220399D01*
X352707Y220413D01*
X352776Y220455D01*
X352860Y220497D01*
X352957Y220552D01*
X353192Y220691D01*
X353470Y220843D01*
X353747Y221037D01*
X354039Y221259D01*
X354330Y221495D01*
X354344Y221509D01*
X354357Y221523D01*
X354399Y221564D01*
X354455Y221606D01*
X354579Y221745D01*
X354746Y221911D01*
X354912Y222105D01*
X355093Y222327D01*
X355245Y222549D01*
X355384Y222785D01*
X356147D01*
Y213146D01*
D02*
G37*
G36*
X491817Y436795D02*
X491942D01*
X492233Y436781D01*
X492538Y436740D01*
X492871Y436698D01*
X493176Y436629D01*
X493329Y436587D01*
X493454Y436545D01*
X493467D01*
X493481Y436531D01*
X493565Y436490D01*
X493689Y436434D01*
X493842Y436337D01*
X494008Y436213D01*
X494189Y436046D01*
X494355Y435852D01*
X494521Y435630D01*
Y435616D01*
X494535Y435602D01*
X494591Y435519D01*
X494646Y435380D01*
X494730Y435200D01*
X494799Y434992D01*
X494868Y434743D01*
X494910Y434479D01*
X494924Y434188D01*
Y434174D01*
Y434146D01*
Y434091D01*
X494910Y434021D01*
Y433924D01*
X494896Y433827D01*
X494841Y433591D01*
X494757Y433314D01*
X494646Y433023D01*
X494480Y432732D01*
X494369Y432593D01*
X494258Y432454D01*
X494244Y432440D01*
X494230Y432426D01*
X494189Y432385D01*
X494133Y432343D01*
X494064Y432288D01*
X493981Y432232D01*
X493870Y432163D01*
X493759Y432080D01*
X493620Y432010D01*
X493467Y431941D01*
X493301Y431858D01*
X493121Y431788D01*
X492913Y431733D01*
X492705Y431664D01*
X492469Y431622D01*
X492219Y431581D01*
X492247Y431567D01*
X492303Y431539D01*
X492386Y431483D01*
X492497Y431428D01*
X492746Y431275D01*
X492871Y431178D01*
X492982Y431095D01*
X493010Y431067D01*
X493079Y430998D01*
X493190Y430887D01*
X493329Y430748D01*
X493481Y430554D01*
X493662Y430346D01*
X493842Y430097D01*
X494036Y429819D01*
X495686Y427212D01*
X494105D01*
X492844Y429209D01*
Y429223D01*
X492816Y429251D01*
X492788Y429292D01*
X492746Y429348D01*
X492649Y429500D01*
X492524Y429694D01*
X492372Y429902D01*
X492219Y430124D01*
X492067Y430332D01*
X491928Y430527D01*
X491914Y430540D01*
X491873Y430596D01*
X491803Y430679D01*
X491706Y430776D01*
X491498Y430984D01*
X491387Y431081D01*
X491276Y431164D01*
X491263Y431178D01*
X491235Y431192D01*
X491179Y431220D01*
X491096Y431261D01*
X491013Y431303D01*
X490916Y431345D01*
X490694Y431414D01*
X490680D01*
X490652Y431428D01*
X490597D01*
X490527Y431442D01*
X490430Y431456D01*
X490319D01*
X490167Y431469D01*
X488530D01*
Y427212D01*
X487254D01*
Y436809D01*
X491706D01*
X491817Y436795D01*
D02*
G37*
G36*
X499764Y436837D02*
X499875Y436823D01*
X500000Y436809D01*
X500138Y436795D01*
X500277Y436753D01*
X500610Y436670D01*
X500943Y436545D01*
X501109Y436462D01*
X501275Y436365D01*
X501428Y436240D01*
X501581Y436115D01*
X501594Y436102D01*
X501608Y436088D01*
X501650Y436046D01*
X501705Y435991D01*
X501761Y435907D01*
X501830Y435824D01*
X501969Y435616D01*
X502108Y435353D01*
X502232Y435048D01*
X502329Y434701D01*
X502343Y434521D01*
X502357Y434326D01*
Y434313D01*
Y434299D01*
Y434216D01*
X502343Y434091D01*
X502316Y433938D01*
X502274Y433744D01*
X502205Y433550D01*
X502121Y433356D01*
X501997Y433162D01*
X501983Y433134D01*
X501927Y433078D01*
X501844Y432995D01*
X501733Y432884D01*
X501581Y432759D01*
X501400Y432635D01*
X501192Y432510D01*
X500943Y432399D01*
X500956D01*
X500984Y432385D01*
X501026Y432371D01*
X501081Y432343D01*
X501248Y432274D01*
X501442Y432177D01*
X501650Y432038D01*
X501872Y431886D01*
X502080Y431691D01*
X502274Y431469D01*
Y431456D01*
X502288Y431442D01*
X502343Y431359D01*
X502426Y431220D01*
X502510Y431040D01*
X502593Y430818D01*
X502676Y430554D01*
X502732Y430263D01*
X502746Y429944D01*
Y429930D01*
Y429888D01*
Y429819D01*
X502732Y429736D01*
X502718Y429639D01*
X502704Y429514D01*
X502676Y429375D01*
X502635Y429223D01*
X502537Y428904D01*
X502468Y428724D01*
X502371Y428557D01*
X502274Y428377D01*
X502163Y428210D01*
X502024Y428044D01*
X501872Y427878D01*
X501858Y427864D01*
X501830Y427836D01*
X501789Y427794D01*
X501719Y427753D01*
X501622Y427683D01*
X501525Y427614D01*
X501400Y427545D01*
X501262Y427462D01*
X501109Y427378D01*
X500929Y427309D01*
X500735Y427240D01*
X500540Y427170D01*
X500318Y427129D01*
X500083Y427087D01*
X499847Y427059D01*
X499584Y427046D01*
X499445D01*
X499348Y427059D01*
X499223Y427073D01*
X499084Y427087D01*
X498932Y427115D01*
X498765Y427156D01*
X498391Y427253D01*
X498197Y427323D01*
X498016Y427392D01*
X497822Y427489D01*
X497628Y427600D01*
X497448Y427725D01*
X497281Y427878D01*
X497267Y427892D01*
X497240Y427919D01*
X497198Y427961D01*
X497143Y428030D01*
X497087Y428113D01*
X497004Y428210D01*
X496935Y428321D01*
X496851Y428460D01*
X496768Y428599D01*
X496699Y428765D01*
X496560Y429112D01*
X496505Y429320D01*
X496463Y429528D01*
X496435Y429750D01*
X496422Y429972D01*
Y429986D01*
Y430013D01*
Y430069D01*
X496435Y430124D01*
Y430207D01*
X496449Y430305D01*
X496477Y430527D01*
X496533Y430776D01*
X496616Y431026D01*
X496740Y431289D01*
X496893Y431539D01*
Y431553D01*
X496921Y431567D01*
X496976Y431636D01*
X497087Y431747D01*
X497240Y431886D01*
X497434Y432024D01*
X497670Y432177D01*
X497933Y432302D01*
X498252Y432399D01*
X498238D01*
X498224Y432413D01*
X498183Y432426D01*
X498127Y432454D01*
X498003Y432510D01*
X497836Y432593D01*
X497656Y432704D01*
X497476Y432842D01*
X497309Y432995D01*
X497156Y433162D01*
X497143Y433189D01*
X497101Y433245D01*
X497046Y433356D01*
X496990Y433494D01*
X496921Y433675D01*
X496865Y433883D01*
X496824Y434118D01*
X496810Y434368D01*
Y434382D01*
Y434410D01*
Y434465D01*
X496824Y434548D01*
X496838Y434632D01*
X496851Y434743D01*
X496907Y434978D01*
X496990Y435256D01*
X497129Y435547D01*
X497212Y435699D01*
X497309Y435852D01*
X497434Y435991D01*
X497559Y436129D01*
X497573Y436143D01*
X497600Y436157D01*
X497642Y436199D01*
X497697Y436240D01*
X497767Y436296D01*
X497864Y436351D01*
X497975Y436421D01*
X498086Y436490D01*
X498224Y436559D01*
X498377Y436629D01*
X498543Y436684D01*
X498724Y436740D01*
X499112Y436823D01*
X499334Y436837D01*
X499556Y436851D01*
X499681D01*
X499764Y436837D01*
D02*
G37*
G36*
X268599Y414699D02*
X268779Y414671D01*
X269001Y414630D01*
X269250Y414560D01*
X269500Y414477D01*
X269750Y414366D01*
X269764D01*
X269777Y414352D01*
X269861Y414311D01*
X269985Y414228D01*
X270124Y414131D01*
X270291Y413992D01*
X270457Y413839D01*
X270623Y413659D01*
X270762Y413451D01*
X270776Y413423D01*
X270818Y413354D01*
X270873Y413229D01*
X270942Y413077D01*
X271012Y412896D01*
X271067Y412688D01*
X271109Y412452D01*
X271123Y412217D01*
Y412189D01*
Y412106D01*
X271109Y411995D01*
X271081Y411842D01*
X271039Y411662D01*
X270970Y411468D01*
X270887Y411274D01*
X270776Y411079D01*
X270762Y411052D01*
X270721Y410996D01*
X270637Y410899D01*
X270526Y410788D01*
X270388Y410663D01*
X270221Y410525D01*
X270027Y410400D01*
X269791Y410275D01*
X269805D01*
X269833Y410261D01*
X269874Y410247D01*
X269930Y410233D01*
X270082Y410178D01*
X270277Y410095D01*
X270499Y409984D01*
X270721Y409845D01*
X270928Y409665D01*
X271123Y409457D01*
X271136Y409429D01*
X271192Y409346D01*
X271275Y409207D01*
X271358Y409027D01*
X271442Y408805D01*
X271525Y408542D01*
X271580Y408236D01*
X271594Y407904D01*
Y407890D01*
Y407848D01*
Y407779D01*
X271580Y407696D01*
X271566Y407585D01*
X271539Y407460D01*
X271511Y407321D01*
X271483Y407169D01*
X271372Y406836D01*
X271289Y406655D01*
X271206Y406489D01*
X271095Y406309D01*
X270970Y406128D01*
X270831Y405948D01*
X270665Y405782D01*
X270651Y405768D01*
X270623Y405740D01*
X270568Y405699D01*
X270499Y405643D01*
X270415Y405574D01*
X270304Y405504D01*
X270180Y405421D01*
X270027Y405352D01*
X269874Y405269D01*
X269694Y405185D01*
X269514Y405116D01*
X269306Y405047D01*
X269084Y404991D01*
X268848Y404950D01*
X268612Y404922D01*
X268349Y404908D01*
X268224D01*
X268141Y404922D01*
X268030Y404936D01*
X267905Y404950D01*
X267766Y404977D01*
X267614Y405005D01*
X267281Y405088D01*
X266934Y405227D01*
X266754Y405310D01*
X266588Y405407D01*
X266421Y405532D01*
X266255Y405657D01*
X266241Y405671D01*
X266213Y405699D01*
X266172Y405740D01*
X266130Y405796D01*
X266061Y405865D01*
X265991Y405962D01*
X265908Y406059D01*
X265825Y406184D01*
X265742Y406323D01*
X265658Y406461D01*
X265506Y406794D01*
X265381Y407182D01*
X265340Y407391D01*
X265312Y407612D01*
X266491Y407765D01*
Y407751D01*
X266504Y407723D01*
X266518Y407668D01*
X266532Y407598D01*
X266546Y407515D01*
X266574Y407418D01*
X266643Y407210D01*
X266740Y406961D01*
X266865Y406725D01*
X267004Y406503D01*
X267170Y406309D01*
X267198Y406295D01*
X267253Y406239D01*
X267364Y406170D01*
X267503Y406101D01*
X267669Y406017D01*
X267877Y405948D01*
X268113Y405893D01*
X268363Y405879D01*
X268446D01*
X268501Y405893D01*
X268654Y405907D01*
X268848Y405948D01*
X269070Y406017D01*
X269306Y406115D01*
X269542Y406253D01*
X269764Y406447D01*
X269791Y406475D01*
X269861Y406558D01*
X269944Y406683D01*
X270055Y406850D01*
X270166Y407058D01*
X270249Y407293D01*
X270318Y407571D01*
X270346Y407876D01*
Y407890D01*
Y407918D01*
Y407959D01*
X270332Y408015D01*
X270318Y408167D01*
X270277Y408347D01*
X270221Y408569D01*
X270124Y408791D01*
X269985Y409013D01*
X269805Y409221D01*
X269777Y409249D01*
X269708Y409304D01*
X269597Y409388D01*
X269445Y409485D01*
X269250Y409582D01*
X269015Y409665D01*
X268751Y409720D01*
X268460Y409748D01*
X268335D01*
X268238Y409734D01*
X268113Y409720D01*
X267974Y409693D01*
X267808Y409665D01*
X267628Y409623D01*
X267766Y410663D01*
X267836D01*
X267891Y410649D01*
X268072D01*
X268224Y410677D01*
X268404Y410705D01*
X268612Y410747D01*
X268848Y410816D01*
X269070Y410913D01*
X269306Y411038D01*
X269320D01*
X269334Y411052D01*
X269403Y411107D01*
X269500Y411204D01*
X269611Y411329D01*
X269722Y411509D01*
X269819Y411717D01*
X269888Y411953D01*
X269916Y412092D01*
Y412244D01*
Y412258D01*
Y412272D01*
Y412355D01*
X269888Y412466D01*
X269861Y412619D01*
X269805Y412785D01*
X269736Y412966D01*
X269625Y413146D01*
X269472Y413312D01*
X269458Y413326D01*
X269389Y413382D01*
X269292Y413451D01*
X269167Y413534D01*
X269001Y413604D01*
X268807Y413673D01*
X268585Y413728D01*
X268335Y413742D01*
X268224D01*
X268099Y413714D01*
X267933Y413687D01*
X267753Y413631D01*
X267572Y413562D01*
X267378Y413451D01*
X267198Y413312D01*
X267184Y413298D01*
X267129Y413229D01*
X267045Y413132D01*
X266948Y412993D01*
X266851Y412813D01*
X266754Y412591D01*
X266671Y412328D01*
X266615Y412023D01*
X265437Y412230D01*
Y412244D01*
X265450Y412286D01*
X265464Y412341D01*
X265478Y412425D01*
X265506Y412522D01*
X265548Y412633D01*
X265631Y412896D01*
X265769Y413201D01*
X265936Y413506D01*
X266144Y413798D01*
X266407Y414061D01*
X266421Y414075D01*
X266449Y414089D01*
X266491Y414117D01*
X266546Y414158D01*
X266615Y414214D01*
X266712Y414269D01*
X266810Y414325D01*
X266934Y414394D01*
X267212Y414505D01*
X267531Y414616D01*
X267905Y414685D01*
X268099Y414713D01*
X268446D01*
X268599Y414699D01*
D02*
G37*
G36*
X260805Y409138D02*
Y405075D01*
X259529D01*
Y409138D01*
X255826Y414671D01*
X257365D01*
X259251Y411759D01*
Y411745D01*
X259279Y411717D01*
X259307Y411676D01*
X259335Y411620D01*
X259390Y411551D01*
X259445Y411468D01*
X259570Y411260D01*
X259723Y411010D01*
X259889Y410733D01*
X260070Y410442D01*
X260236Y410136D01*
Y410150D01*
X260250Y410178D01*
X260278Y410220D01*
X260319Y410275D01*
X260361Y410344D01*
X260416Y410428D01*
X260541Y410636D01*
X260694Y410885D01*
X260874Y411176D01*
X261082Y411496D01*
X261304Y411842D01*
X263148Y414671D01*
X264632D01*
X260805Y409138D01*
D02*
G37*
G36*
X353852Y402649D02*
X353879Y402622D01*
X353935Y402566D01*
X354018Y402511D01*
X354115Y402428D01*
X354226Y402317D01*
X354365Y402206D01*
X354531Y402081D01*
X354698Y401956D01*
X354892Y401804D01*
X355114Y401651D01*
X355336Y401498D01*
X355585Y401332D01*
X355849Y401166D01*
X356140Y400999D01*
X356431Y400833D01*
X356445Y400819D01*
X356501Y400791D01*
X356584Y400750D01*
X356708Y400680D01*
X356861Y400611D01*
X357028Y400528D01*
X357222Y400430D01*
X357444Y400334D01*
X357693Y400223D01*
X357943Y400098D01*
X358220Y399987D01*
X358511Y399876D01*
X359108Y399654D01*
X359746Y399446D01*
X359760D01*
X359801Y399432D01*
X359870Y399418D01*
X359954Y399390D01*
X360065Y399363D01*
X360203Y399335D01*
X360356Y399293D01*
X360522Y399266D01*
X360717Y399224D01*
X360924Y399182D01*
X361368Y399113D01*
X361854Y399044D01*
X362381Y399002D01*
Y397795D01*
X362367D01*
X362325D01*
X362270D01*
X362187Y397809D01*
X362076D01*
X361937Y397823D01*
X361784Y397837D01*
X361618Y397851D01*
X361424Y397879D01*
X361230Y397906D01*
X360994Y397948D01*
X360758Y397990D01*
X360508Y398031D01*
X360231Y398087D01*
X359663Y398226D01*
X359649D01*
X359593Y398239D01*
X359510Y398267D01*
X359385Y398309D01*
X359246Y398350D01*
X359080Y398406D01*
X358886Y398461D01*
X358678Y398544D01*
X358442Y398628D01*
X358206Y398711D01*
X357679Y398919D01*
X357125Y399169D01*
X356570Y399446D01*
X356556Y399460D01*
X356501Y399487D01*
X356431Y399529D01*
X356320Y399585D01*
X356195Y399654D01*
X356043Y399751D01*
X355876Y399848D01*
X355696Y399959D01*
X355294Y400223D01*
X354878Y400500D01*
X354448Y400819D01*
X354046Y401152D01*
Y396450D01*
X352909D01*
Y402663D01*
X353838D01*
X353852Y402649D01*
D02*
G37*
G36*
X362381Y392165D02*
X354878D01*
X354892Y392151D01*
X354947Y392082D01*
X355031Y391999D01*
X355127Y391860D01*
X355252Y391707D01*
X355391Y391513D01*
X355544Y391291D01*
X355696Y391042D01*
Y391028D01*
X355710Y391014D01*
X355765Y390931D01*
X355835Y390792D01*
X355918Y390626D01*
X356015Y390431D01*
X356112Y390223D01*
X356209Y390015D01*
X356292Y389807D01*
X355155D01*
Y389821D01*
X355127Y389849D01*
X355114Y389904D01*
X355072Y389974D01*
X355031Y390057D01*
X354975Y390154D01*
X354836Y390390D01*
X354684Y390667D01*
X354490Y390945D01*
X354268Y391236D01*
X354032Y391527D01*
X354018Y391541D01*
X354004Y391555D01*
X353963Y391596D01*
X353921Y391652D01*
X353782Y391777D01*
X353616Y391943D01*
X353422Y392109D01*
X353200Y392290D01*
X352978Y392442D01*
X352742Y392581D01*
Y393344D01*
X362381D01*
Y392165D01*
D02*
G37*
G36*
X359413Y387810D02*
X359496Y387783D01*
X359607Y387741D01*
X359732Y387699D01*
X359884Y387644D01*
X360051Y387575D01*
X360231Y387491D01*
X360619Y387297D01*
X361008Y387048D01*
X361202Y386895D01*
X361396Y386742D01*
X361562Y386576D01*
X361729Y386382D01*
X361743Y386368D01*
X361771Y386340D01*
X361798Y386271D01*
X361854Y386202D01*
X361923Y386091D01*
X361992Y385980D01*
X362062Y385827D01*
X362131Y385675D01*
X362214Y385494D01*
X362284Y385300D01*
X362353Y385092D01*
X362422Y384870D01*
X362478Y384634D01*
X362505Y384385D01*
X362533Y384121D01*
X362547Y383844D01*
Y383691D01*
X362533Y383580D01*
Y383456D01*
X362519Y383303D01*
X362492Y383137D01*
X362464Y382943D01*
X362395Y382540D01*
X362284Y382124D01*
X362131Y381708D01*
X362034Y381514D01*
X361923Y381320D01*
X361909Y381306D01*
X361895Y381278D01*
X361854Y381223D01*
X361798Y381167D01*
X361743Y381084D01*
X361660Y380987D01*
X361562Y380876D01*
X361451Y380765D01*
X361327Y380654D01*
X361202Y380529D01*
X360883Y380280D01*
X360508Y380044D01*
X360092Y379836D01*
X360079D01*
X360037Y379808D01*
X359968Y379794D01*
X359884Y379753D01*
X359773Y379725D01*
X359635Y379683D01*
X359482Y379628D01*
X359316Y379586D01*
X359136Y379545D01*
X358927Y379489D01*
X358498Y379420D01*
X358012Y379364D01*
X357513Y379337D01*
X357499D01*
X357444D01*
X357360D01*
X357263Y379351D01*
X357125D01*
X356986Y379364D01*
X356806Y379378D01*
X356625Y379406D01*
X356223Y379475D01*
X355779Y379572D01*
X355336Y379711D01*
X354906Y379905D01*
X354892Y379919D01*
X354850Y379933D01*
X354795Y379961D01*
X354725Y380016D01*
X354628Y380072D01*
X354517Y380141D01*
X354268Y380321D01*
X353990Y380557D01*
X353713Y380835D01*
X353436Y381153D01*
X353200Y381528D01*
X353186Y381542D01*
X353172Y381583D01*
X353144Y381639D01*
X353103Y381708D01*
X353061Y381819D01*
X353019Y381930D01*
X352964Y382069D01*
X352909Y382221D01*
X352853Y382388D01*
X352798Y382568D01*
X352714Y382956D01*
X352645Y383400D01*
X352617Y383858D01*
Y383997D01*
X352631Y384094D01*
X352645Y384218D01*
X352659Y384371D01*
X352673Y384524D01*
X352714Y384704D01*
X352798Y385078D01*
X352923Y385494D01*
X353006Y385702D01*
X353103Y385896D01*
X353228Y386091D01*
X353352Y386285D01*
X353366Y386299D01*
X353380Y386326D01*
X353422Y386382D01*
X353491Y386451D01*
X353560Y386521D01*
X353657Y386618D01*
X353768Y386715D01*
X353879Y386826D01*
X354018Y386937D01*
X354184Y387048D01*
X354351Y387172D01*
X354531Y387283D01*
X354739Y387380D01*
X354947Y387491D01*
X355169Y387575D01*
X355419Y387658D01*
X355710Y386410D01*
X355696D01*
X355668Y386396D01*
X355613Y386368D01*
X355544Y386340D01*
X355460Y386312D01*
X355349Y386271D01*
X355127Y386160D01*
X354878Y386021D01*
X354628Y385855D01*
X354393Y385647D01*
X354184Y385425D01*
X354157Y385397D01*
X354101Y385314D01*
X354032Y385175D01*
X353935Y384995D01*
X353852Y384759D01*
X353768Y384496D01*
X353713Y384177D01*
X353699Y383830D01*
Y383719D01*
X353713Y383650D01*
Y383553D01*
X353727Y383442D01*
X353768Y383178D01*
X353824Y382887D01*
X353921Y382582D01*
X354060Y382263D01*
X354240Y381972D01*
Y381958D01*
X354268Y381944D01*
X354337Y381847D01*
X354448Y381722D01*
X354614Y381570D01*
X354822Y381389D01*
X355058Y381223D01*
X355349Y381070D01*
X355668Y380932D01*
X355682D01*
X355710Y380918D01*
X355752Y380904D01*
X355821Y380890D01*
X355904Y380862D01*
X356001Y380835D01*
X356237Y380793D01*
X356514Y380737D01*
X356819Y380682D01*
X357152Y380654D01*
X357513Y380640D01*
X357527D01*
X357568D01*
X357638D01*
X357721D01*
X357818Y380654D01*
X357943D01*
X358082Y380668D01*
X358234Y380682D01*
X358567Y380723D01*
X358927Y380793D01*
X359288Y380876D01*
X359649Y380987D01*
X359663D01*
X359690Y381001D01*
X359732Y381029D01*
X359801Y381056D01*
X359968Y381140D01*
X360162Y381264D01*
X360384Y381417D01*
X360619Y381611D01*
X360827Y381833D01*
X361022Y382096D01*
Y382110D01*
X361035Y382138D01*
X361063Y382180D01*
X361091Y382235D01*
X361119Y382304D01*
X361160Y382388D01*
X361244Y382582D01*
X361327Y382831D01*
X361396Y383109D01*
X361451Y383414D01*
X361465Y383733D01*
Y383830D01*
X361451Y383913D01*
Y384010D01*
X361438Y384107D01*
X361382Y384357D01*
X361313Y384648D01*
X361202Y384939D01*
X361049Y385245D01*
X360966Y385397D01*
X360855Y385536D01*
X360841Y385550D01*
X360827Y385564D01*
X360786Y385605D01*
X360744Y385661D01*
X360675Y385716D01*
X360592Y385785D01*
X360508Y385869D01*
X360397Y385938D01*
X360273Y386021D01*
X360134Y386118D01*
X359995Y386202D01*
X359829Y386285D01*
X359649Y386354D01*
X359454Y386423D01*
X359246Y386493D01*
X359025Y386548D01*
X359343Y387824D01*
X359357D01*
X359413Y387810D01*
D02*
G37*
G36*
X133819Y76074D02*
X133805D01*
X133750D01*
X133667D01*
X133556Y76088D01*
X133431Y76102D01*
X133292Y76130D01*
X133154Y76158D01*
X133001Y76213D01*
X132987D01*
X132973Y76227D01*
X132890Y76255D01*
X132765Y76310D01*
X132599Y76393D01*
X132405Y76504D01*
X132183Y76643D01*
X131961Y76796D01*
X131725Y76990D01*
X131711D01*
X131697Y77017D01*
X131614Y77087D01*
X131489Y77212D01*
X131309Y77392D01*
X131101Y77600D01*
X130851Y77863D01*
X130574Y78182D01*
X130283Y78529D01*
X130269Y78543D01*
X130227Y78598D01*
X130158Y78682D01*
X130075Y78779D01*
X129964Y78904D01*
X129839Y79056D01*
X129700Y79209D01*
X129548Y79389D01*
X129215Y79736D01*
X128882Y80082D01*
X128716Y80249D01*
X128549Y80401D01*
X128397Y80540D01*
X128244Y80651D01*
X128230D01*
X128216Y80679D01*
X128175Y80706D01*
X128119Y80734D01*
X127967Y80831D01*
X127787Y80942D01*
X127565Y81039D01*
X127329Y81136D01*
X127065Y81192D01*
X126816Y81220D01*
X126802D01*
X126788D01*
X126705Y81206D01*
X126566Y81192D01*
X126413Y81150D01*
X126219Y81095D01*
X126025Y80998D01*
X125831Y80873D01*
X125637Y80706D01*
X125609Y80679D01*
X125554Y80609D01*
X125484Y80512D01*
X125387Y80360D01*
X125304Y80166D01*
X125221Y79944D01*
X125165Y79680D01*
X125152Y79389D01*
Y79306D01*
X125165Y79250D01*
X125179Y79084D01*
X125221Y78890D01*
X125276Y78682D01*
X125373Y78446D01*
X125498Y78224D01*
X125665Y78016D01*
X125692Y77988D01*
X125762Y77933D01*
X125873Y77850D01*
X126039Y77766D01*
X126233Y77669D01*
X126483Y77586D01*
X126760Y77531D01*
X127079Y77503D01*
X126954Y76296D01*
X126940D01*
X126899Y76310D01*
X126830D01*
X126733Y76324D01*
X126622Y76352D01*
X126497Y76379D01*
X126344Y76421D01*
X126192Y76463D01*
X125859Y76574D01*
X125526Y76740D01*
X125359Y76837D01*
X125193Y76962D01*
X125041Y77087D01*
X124902Y77225D01*
X124888Y77239D01*
X124874Y77267D01*
X124832Y77309D01*
X124791Y77378D01*
X124735Y77461D01*
X124680Y77558D01*
X124611Y77669D01*
X124541Y77808D01*
X124472Y77961D01*
X124403Y78127D01*
X124347Y78307D01*
X124292Y78501D01*
X124250Y78709D01*
X124208Y78931D01*
X124195Y79167D01*
X124181Y79417D01*
Y79555D01*
X124195Y79652D01*
X124208Y79763D01*
X124222Y79902D01*
X124250Y80055D01*
X124278Y80207D01*
X124375Y80568D01*
X124514Y80928D01*
X124597Y81109D01*
X124694Y81289D01*
X124819Y81455D01*
X124957Y81608D01*
X124971Y81622D01*
X124985Y81650D01*
X125041Y81677D01*
X125096Y81733D01*
X125165Y81802D01*
X125262Y81871D01*
X125359Y81941D01*
X125484Y82024D01*
X125748Y82163D01*
X126081Y82301D01*
X126247Y82357D01*
X126441Y82385D01*
X126635Y82412D01*
X126843Y82426D01*
X126871D01*
X126940D01*
X127051Y82412D01*
X127204Y82398D01*
X127370Y82371D01*
X127565Y82315D01*
X127773Y82260D01*
X127981Y82177D01*
X128008Y82163D01*
X128078Y82135D01*
X128189Y82079D01*
X128341Y81996D01*
X128508Y81885D01*
X128716Y81747D01*
X128924Y81580D01*
X129159Y81386D01*
X129187Y81358D01*
X129270Y81289D01*
X129340Y81220D01*
X129409Y81150D01*
X129492Y81067D01*
X129603Y80956D01*
X129714Y80845D01*
X129839Y80706D01*
X129978Y80568D01*
X130130Y80401D01*
X130283Y80221D01*
X130463Y80027D01*
X130643Y79805D01*
X130837Y79583D01*
X130851Y79569D01*
X130879Y79542D01*
X130921Y79486D01*
X130976Y79417D01*
X131059Y79334D01*
X131143Y79236D01*
X131323Y79015D01*
X131531Y78779D01*
X131739Y78557D01*
X131919Y78363D01*
X131989Y78280D01*
X132058Y78210D01*
X132072Y78196D01*
X132113Y78155D01*
X132169Y78099D01*
X132252Y78030D01*
X132349Y77961D01*
X132446Y77877D01*
X132682Y77711D01*
Y82440D01*
X133819D01*
Y76074D01*
D02*
G37*
G36*
Y73911D02*
X131822Y72649D01*
X131808D01*
X131781Y72621D01*
X131739Y72593D01*
X131684Y72552D01*
X131531Y72455D01*
X131337Y72330D01*
X131129Y72177D01*
X130907Y72025D01*
X130699Y71872D01*
X130505Y71734D01*
X130491Y71720D01*
X130435Y71678D01*
X130352Y71609D01*
X130255Y71512D01*
X130047Y71304D01*
X129950Y71193D01*
X129867Y71082D01*
X129853Y71068D01*
X129839Y71040D01*
X129811Y70985D01*
X129770Y70901D01*
X129728Y70818D01*
X129686Y70721D01*
X129617Y70499D01*
Y70485D01*
X129603Y70458D01*
Y70402D01*
X129589Y70333D01*
X129576Y70236D01*
Y70125D01*
X129562Y69972D01*
Y68336D01*
X133819D01*
Y67060D01*
X124222D01*
Y71512D01*
X124236Y71623D01*
Y71747D01*
X124250Y72039D01*
X124292Y72344D01*
X124333Y72677D01*
X124403Y72982D01*
X124444Y73134D01*
X124486Y73259D01*
Y73273D01*
X124500Y73287D01*
X124541Y73370D01*
X124597Y73495D01*
X124694Y73647D01*
X124819Y73814D01*
X124985Y73994D01*
X125179Y74161D01*
X125401Y74327D01*
X125415D01*
X125429Y74341D01*
X125512Y74396D01*
X125651Y74452D01*
X125831Y74535D01*
X126039Y74604D01*
X126289Y74674D01*
X126552Y74715D01*
X126843Y74729D01*
X126857D01*
X126885D01*
X126940D01*
X127010Y74715D01*
X127107D01*
X127204Y74701D01*
X127440Y74646D01*
X127717Y74563D01*
X128008Y74452D01*
X128300Y74285D01*
X128438Y74174D01*
X128577Y74064D01*
X128591Y74050D01*
X128605Y74036D01*
X128646Y73994D01*
X128688Y73939D01*
X128743Y73869D01*
X128799Y73786D01*
X128868Y73675D01*
X128951Y73564D01*
X129021Y73425D01*
X129090Y73273D01*
X129173Y73107D01*
X129243Y72926D01*
X129298Y72718D01*
X129368Y72510D01*
X129409Y72274D01*
X129451Y72025D01*
X129465Y72053D01*
X129492Y72108D01*
X129548Y72191D01*
X129603Y72302D01*
X129756Y72552D01*
X129853Y72677D01*
X129936Y72788D01*
X129964Y72815D01*
X130033Y72885D01*
X130144Y72996D01*
X130283Y73134D01*
X130477Y73287D01*
X130685Y73467D01*
X130935Y73647D01*
X131212Y73842D01*
X133819Y75492D01*
Y73911D01*
D02*
G37*
G36*
X55459Y157576D02*
X55556D01*
X55667Y157562D01*
X55931Y157507D01*
X56222Y157437D01*
X56527Y157327D01*
X56832Y157160D01*
X56985Y157063D01*
X57123Y156952D01*
X57137Y156938D01*
X57151Y156924D01*
X57193Y156883D01*
X57234Y156841D01*
X57304Y156772D01*
X57359Y156689D01*
X57512Y156495D01*
X57664Y156245D01*
X57803Y155940D01*
X57928Y155593D01*
X58011Y155205D01*
X56832Y155108D01*
Y155121D01*
X56818Y155135D01*
X56804Y155219D01*
X56763Y155343D01*
X56707Y155496D01*
X56652Y155662D01*
X56568Y155829D01*
X56471Y155981D01*
X56374Y156106D01*
X56347Y156134D01*
X56291Y156189D01*
X56194Y156273D01*
X56055Y156370D01*
X55875Y156453D01*
X55681Y156536D01*
X55445Y156592D01*
X55195Y156619D01*
X55098D01*
X54988Y156605D01*
X54863Y156578D01*
X54696Y156536D01*
X54530Y156481D01*
X54363Y156411D01*
X54197Y156300D01*
X54169Y156286D01*
X54100Y156231D01*
X54003Y156134D01*
X53878Y155995D01*
X53739Y155829D01*
X53587Y155635D01*
X53448Y155385D01*
X53309Y155108D01*
Y155094D01*
X53295Y155066D01*
X53282Y155024D01*
X53254Y154969D01*
X53240Y154886D01*
X53212Y154789D01*
X53185Y154678D01*
X53157Y154539D01*
X53115Y154387D01*
X53088Y154220D01*
X53060Y154040D01*
X53046Y153846D01*
X53018Y153624D01*
X53004Y153402D01*
X52990Y153152D01*
Y152903D01*
X53004Y152916D01*
X53060Y153000D01*
X53157Y153111D01*
X53282Y153249D01*
X53420Y153416D01*
X53601Y153568D01*
X53795Y153721D01*
X54017Y153860D01*
X54030D01*
X54044Y153873D01*
X54128Y153915D01*
X54252Y153957D01*
X54419Y154026D01*
X54613Y154081D01*
X54835Y154123D01*
X55071Y154165D01*
X55320Y154178D01*
X55431D01*
X55514Y154165D01*
X55625Y154151D01*
X55736Y154137D01*
X55875Y154109D01*
X56014Y154067D01*
X56333Y153970D01*
X56499Y153901D01*
X56666Y153804D01*
X56832Y153707D01*
X57012Y153596D01*
X57179Y153457D01*
X57331Y153305D01*
X57345Y153291D01*
X57373Y153263D01*
X57414Y153222D01*
X57456Y153152D01*
X57525Y153055D01*
X57595Y152958D01*
X57664Y152833D01*
X57747Y152695D01*
X57831Y152542D01*
X57900Y152376D01*
X57969Y152181D01*
X58039Y151987D01*
X58080Y151779D01*
X58122Y151544D01*
X58149Y151308D01*
X58163Y151058D01*
Y151044D01*
Y151017D01*
Y150975D01*
Y150906D01*
X58149Y150822D01*
Y150739D01*
X58108Y150517D01*
X58066Y150254D01*
X57997Y149976D01*
X57900Y149671D01*
X57761Y149380D01*
Y149366D01*
X57747Y149352D01*
X57719Y149311D01*
X57692Y149255D01*
X57609Y149116D01*
X57484Y148936D01*
X57331Y148742D01*
X57151Y148548D01*
X56929Y148354D01*
X56693Y148187D01*
X56679D01*
X56666Y148173D01*
X56624Y148146D01*
X56568Y148132D01*
X56430Y148062D01*
X56249Y147993D01*
X56014Y147910D01*
X55750Y147854D01*
X55459Y147799D01*
X55140Y147785D01*
X55071D01*
X55001Y147799D01*
X54890D01*
X54766Y147813D01*
X54627Y147841D01*
X54461Y147882D01*
X54294Y147924D01*
X54100Y147979D01*
X53906Y148049D01*
X53712Y148132D01*
X53504Y148243D01*
X53309Y148368D01*
X53115Y148506D01*
X52921Y148673D01*
X52741Y148867D01*
X52727Y148881D01*
X52699Y148922D01*
X52658Y148978D01*
X52602Y149075D01*
X52519Y149200D01*
X52450Y149338D01*
X52366Y149519D01*
X52283Y149713D01*
X52186Y149949D01*
X52103Y150212D01*
X52034Y150503D01*
X51964Y150822D01*
X51895Y151183D01*
X51853Y151571D01*
X51825Y151987D01*
X51812Y152431D01*
Y152445D01*
Y152459D01*
Y152500D01*
Y152556D01*
X51825Y152695D01*
Y152889D01*
X51839Y153111D01*
X51867Y153374D01*
X51895Y153665D01*
X51936Y153984D01*
X51992Y154303D01*
X52061Y154650D01*
X52144Y154983D01*
X52242Y155316D01*
X52366Y155635D01*
X52505Y155940D01*
X52658Y156231D01*
X52838Y156481D01*
X52852Y156495D01*
X52880Y156522D01*
X52935Y156578D01*
X53004Y156661D01*
X53088Y156744D01*
X53198Y156827D01*
X53337Y156938D01*
X53476Y157035D01*
X53642Y157132D01*
X53822Y157243D01*
X54030Y157327D01*
X54239Y157424D01*
X54474Y157493D01*
X54724Y157549D01*
X54988Y157576D01*
X55265Y157590D01*
X55376D01*
X55459Y157576D01*
D02*
G37*
G36*
X39594Y157701D02*
X39718Y157687D01*
X39871Y157673D01*
X40023Y157659D01*
X40204Y157618D01*
X40578Y157535D01*
X40994Y157410D01*
X41202Y157327D01*
X41396Y157229D01*
X41591Y157105D01*
X41785Y156980D01*
X41799Y156966D01*
X41826Y156952D01*
X41882Y156910D01*
X41951Y156841D01*
X42021Y156772D01*
X42118Y156675D01*
X42215Y156564D01*
X42326Y156453D01*
X42437Y156314D01*
X42547Y156148D01*
X42672Y155981D01*
X42783Y155801D01*
X42880Y155593D01*
X42991Y155385D01*
X43074Y155163D01*
X43158Y154914D01*
X41910Y154622D01*
Y154636D01*
X41896Y154664D01*
X41868Y154719D01*
X41840Y154789D01*
X41813Y154872D01*
X41771Y154983D01*
X41660Y155205D01*
X41521Y155454D01*
X41355Y155704D01*
X41147Y155940D01*
X40925Y156148D01*
X40897Y156175D01*
X40814Y156231D01*
X40675Y156300D01*
X40495Y156397D01*
X40259Y156481D01*
X39996Y156564D01*
X39677Y156619D01*
X39330Y156633D01*
X39219D01*
X39150Y156619D01*
X39053D01*
X38942Y156605D01*
X38678Y156564D01*
X38387Y156508D01*
X38082Y156411D01*
X37763Y156273D01*
X37472Y156092D01*
X37458D01*
X37444Y156065D01*
X37347Y155995D01*
X37222Y155884D01*
X37069Y155718D01*
X36889Y155510D01*
X36723Y155274D01*
X36570Y154983D01*
X36432Y154664D01*
Y154650D01*
X36418Y154622D01*
X36404Y154581D01*
X36390Y154511D01*
X36362Y154428D01*
X36335Y154331D01*
X36293Y154095D01*
X36237Y153818D01*
X36182Y153513D01*
X36154Y153180D01*
X36140Y152819D01*
Y152806D01*
Y152764D01*
Y152695D01*
Y152611D01*
X36154Y152514D01*
Y152389D01*
X36168Y152251D01*
X36182Y152098D01*
X36223Y151765D01*
X36293Y151405D01*
X36376Y151044D01*
X36487Y150684D01*
Y150670D01*
X36501Y150642D01*
X36529Y150600D01*
X36556Y150531D01*
X36640Y150365D01*
X36764Y150170D01*
X36917Y149949D01*
X37111Y149713D01*
X37333Y149505D01*
X37596Y149311D01*
X37610D01*
X37638Y149297D01*
X37680Y149269D01*
X37735Y149241D01*
X37805Y149214D01*
X37888Y149172D01*
X38082Y149089D01*
X38331Y149005D01*
X38609Y148936D01*
X38914Y148881D01*
X39233Y148867D01*
X39330D01*
X39413Y148881D01*
X39510D01*
X39607Y148895D01*
X39857Y148950D01*
X40148Y149019D01*
X40440Y149130D01*
X40745Y149283D01*
X40897Y149366D01*
X41036Y149477D01*
X41050Y149491D01*
X41064Y149505D01*
X41105Y149546D01*
X41161Y149588D01*
X41216Y149657D01*
X41286Y149741D01*
X41369Y149824D01*
X41438Y149935D01*
X41521Y150059D01*
X41618Y150198D01*
X41701Y150337D01*
X41785Y150503D01*
X41854Y150684D01*
X41923Y150878D01*
X41993Y151086D01*
X42048Y151308D01*
X43324Y150989D01*
Y150975D01*
X43310Y150919D01*
X43282Y150836D01*
X43241Y150725D01*
X43199Y150600D01*
X43144Y150448D01*
X43074Y150281D01*
X42991Y150101D01*
X42797Y149713D01*
X42547Y149325D01*
X42395Y149130D01*
X42242Y148936D01*
X42076Y148770D01*
X41882Y148603D01*
X41868Y148589D01*
X41840Y148562D01*
X41771Y148534D01*
X41701Y148478D01*
X41591Y148409D01*
X41480Y148340D01*
X41327Y148271D01*
X41175Y148201D01*
X40994Y148118D01*
X40800Y148049D01*
X40592Y147979D01*
X40370Y147910D01*
X40134Y147854D01*
X39885Y147827D01*
X39621Y147799D01*
X39344Y147785D01*
X39191D01*
X39080Y147799D01*
X38956D01*
X38803Y147813D01*
X38637Y147841D01*
X38442Y147868D01*
X38040Y147938D01*
X37624Y148049D01*
X37208Y148201D01*
X37014Y148298D01*
X36820Y148409D01*
X36806Y148423D01*
X36778Y148437D01*
X36723Y148478D01*
X36667Y148534D01*
X36584Y148589D01*
X36487Y148673D01*
X36376Y148770D01*
X36265Y148881D01*
X36154Y149005D01*
X36029Y149130D01*
X35780Y149449D01*
X35544Y149824D01*
X35336Y150240D01*
Y150254D01*
X35308Y150295D01*
X35294Y150365D01*
X35253Y150448D01*
X35225Y150559D01*
X35183Y150697D01*
X35128Y150850D01*
X35086Y151017D01*
X35045Y151197D01*
X34989Y151405D01*
X34920Y151835D01*
X34864Y152320D01*
X34837Y152819D01*
Y152833D01*
Y152889D01*
Y152972D01*
X34851Y153069D01*
Y153208D01*
X34864Y153346D01*
X34878Y153527D01*
X34906Y153707D01*
X34975Y154109D01*
X35072Y154553D01*
X35211Y154997D01*
X35405Y155427D01*
X35419Y155441D01*
X35433Y155482D01*
X35461Y155538D01*
X35516Y155607D01*
X35572Y155704D01*
X35641Y155815D01*
X35821Y156065D01*
X36057Y156342D01*
X36335Y156619D01*
X36653Y156897D01*
X37028Y157132D01*
X37042Y157146D01*
X37083Y157160D01*
X37139Y157188D01*
X37208Y157229D01*
X37319Y157271D01*
X37430Y157313D01*
X37569Y157368D01*
X37721Y157424D01*
X37888Y157479D01*
X38068Y157535D01*
X38456Y157618D01*
X38900Y157687D01*
X39358Y157715D01*
X39497D01*
X39594Y157701D01*
D02*
G37*
G36*
X48844Y147951D02*
X47665D01*
Y155454D01*
X47651Y155441D01*
X47582Y155385D01*
X47498Y155302D01*
X47360Y155205D01*
X47207Y155080D01*
X47013Y154941D01*
X46791Y154789D01*
X46542Y154636D01*
X46528D01*
X46514Y154622D01*
X46431Y154567D01*
X46292Y154497D01*
X46126Y154414D01*
X45931Y154317D01*
X45723Y154220D01*
X45515Y154123D01*
X45307Y154040D01*
Y155177D01*
X45321D01*
X45349Y155205D01*
X45404Y155219D01*
X45474Y155260D01*
X45557Y155302D01*
X45654Y155357D01*
X45890Y155496D01*
X46167Y155648D01*
X46445Y155843D01*
X46736Y156065D01*
X47027Y156300D01*
X47041Y156314D01*
X47055Y156328D01*
X47096Y156370D01*
X47152Y156411D01*
X47277Y156550D01*
X47443Y156716D01*
X47610Y156910D01*
X47790Y157132D01*
X47942Y157354D01*
X48081Y157590D01*
X48844D01*
Y147951D01*
D02*
G37*
G36*
X141114Y173389D02*
X141239Y173375D01*
X141391Y173361D01*
X141544Y173347D01*
X141724Y173305D01*
X142099Y173222D01*
X142515Y173097D01*
X142723Y173014D01*
X142917Y172917D01*
X143111Y172792D01*
X143305Y172668D01*
X143319Y172654D01*
X143347Y172640D01*
X143402Y172598D01*
X143472Y172529D01*
X143541Y172459D01*
X143638Y172362D01*
X143735Y172251D01*
X143846Y172141D01*
X143957Y172002D01*
X144068Y171835D01*
X144193Y171669D01*
X144304Y171489D01*
X144401Y171281D01*
X144512Y171073D01*
X144595Y170851D01*
X144678Y170601D01*
X143430Y170310D01*
Y170324D01*
X143416Y170351D01*
X143388Y170407D01*
X143361Y170476D01*
X143333Y170560D01*
X143291Y170670D01*
X143180Y170892D01*
X143042Y171142D01*
X142875Y171392D01*
X142667Y171627D01*
X142445Y171835D01*
X142418Y171863D01*
X142334Y171919D01*
X142196Y171988D01*
X142015Y172085D01*
X141780Y172168D01*
X141516Y172251D01*
X141197Y172307D01*
X140850Y172321D01*
X140739D01*
X140670Y172307D01*
X140573D01*
X140462Y172293D01*
X140199Y172251D01*
X139907Y172196D01*
X139602Y172099D01*
X139283Y171960D01*
X138992Y171780D01*
X138978D01*
X138964Y171752D01*
X138867Y171683D01*
X138743Y171572D01*
X138590Y171405D01*
X138410Y171197D01*
X138243Y170962D01*
X138091Y170670D01*
X137952Y170351D01*
Y170338D01*
X137938Y170310D01*
X137924Y170268D01*
X137910Y170199D01*
X137883Y170116D01*
X137855Y170019D01*
X137813Y169783D01*
X137758Y169506D01*
X137702Y169200D01*
X137675Y168867D01*
X137661Y168507D01*
Y168493D01*
Y168451D01*
Y168382D01*
Y168299D01*
X137675Y168202D01*
Y168077D01*
X137689Y167938D01*
X137702Y167786D01*
X137744Y167453D01*
X137813Y167092D01*
X137896Y166732D01*
X138007Y166371D01*
Y166357D01*
X138021Y166330D01*
X138049Y166288D01*
X138077Y166219D01*
X138160Y166052D01*
X138285Y165858D01*
X138437Y165636D01*
X138631Y165400D01*
X138853Y165192D01*
X139117Y164998D01*
X139131D01*
X139158Y164984D01*
X139200Y164957D01*
X139256Y164929D01*
X139325Y164901D01*
X139408Y164860D01*
X139602Y164776D01*
X139852Y164693D01*
X140129Y164624D01*
X140434Y164568D01*
X140753Y164555D01*
X140850D01*
X140934Y164568D01*
X141031D01*
X141128Y164582D01*
X141377Y164638D01*
X141669Y164707D01*
X141960Y164818D01*
X142265Y164970D01*
X142418Y165054D01*
X142556Y165165D01*
X142570Y165179D01*
X142584Y165192D01*
X142626Y165234D01*
X142681Y165276D01*
X142737Y165345D01*
X142806Y165428D01*
X142889Y165511D01*
X142958Y165622D01*
X143042Y165747D01*
X143139Y165886D01*
X143222Y166024D01*
X143305Y166191D01*
X143375Y166371D01*
X143444Y166565D01*
X143513Y166773D01*
X143569Y166995D01*
X144845Y166676D01*
Y166663D01*
X144831Y166607D01*
X144803Y166524D01*
X144761Y166413D01*
X144720Y166288D01*
X144664Y166136D01*
X144595Y165969D01*
X144512Y165789D01*
X144318Y165400D01*
X144068Y165012D01*
X143915Y164818D01*
X143763Y164624D01*
X143596Y164457D01*
X143402Y164291D01*
X143388Y164277D01*
X143361Y164249D01*
X143291Y164222D01*
X143222Y164166D01*
X143111Y164097D01*
X143000Y164028D01*
X142847Y163958D01*
X142695Y163889D01*
X142515Y163806D01*
X142320Y163736D01*
X142113Y163667D01*
X141891Y163598D01*
X141655Y163542D01*
X141405Y163514D01*
X141142Y163487D01*
X140864Y163473D01*
X140712D01*
X140601Y163487D01*
X140476D01*
X140323Y163500D01*
X140157Y163528D01*
X139963Y163556D01*
X139561Y163625D01*
X139145Y163736D01*
X138729Y163889D01*
X138534Y163986D01*
X138340Y164097D01*
X138326Y164111D01*
X138299Y164125D01*
X138243Y164166D01*
X138188Y164222D01*
X138104Y164277D01*
X138007Y164360D01*
X137896Y164457D01*
X137786Y164568D01*
X137675Y164693D01*
X137550Y164818D01*
X137300Y165137D01*
X137064Y165511D01*
X136856Y165927D01*
Y165941D01*
X136829Y165983D01*
X136815Y166052D01*
X136773Y166136D01*
X136745Y166246D01*
X136704Y166385D01*
X136648Y166538D01*
X136607Y166704D01*
X136565Y166884D01*
X136510Y167092D01*
X136440Y167522D01*
X136385Y168008D01*
X136357Y168507D01*
Y168521D01*
Y168576D01*
Y168659D01*
X136371Y168757D01*
Y168895D01*
X136385Y169034D01*
X136399Y169214D01*
X136426Y169394D01*
X136496Y169797D01*
X136593Y170240D01*
X136732Y170684D01*
X136926Y171114D01*
X136940Y171128D01*
X136953Y171170D01*
X136981Y171225D01*
X137037Y171294D01*
X137092Y171392D01*
X137162Y171502D01*
X137342Y171752D01*
X137578Y172029D01*
X137855Y172307D01*
X138174Y172584D01*
X138548Y172820D01*
X138562Y172834D01*
X138604Y172848D01*
X138659Y172875D01*
X138729Y172917D01*
X138840Y172959D01*
X138951Y173000D01*
X139089Y173056D01*
X139242Y173111D01*
X139408Y173167D01*
X139588Y173222D01*
X139977Y173305D01*
X140421Y173375D01*
X140878Y173403D01*
X141017D01*
X141114Y173389D01*
D02*
G37*
G36*
X151834Y171988D02*
X147993D01*
X147480Y169394D01*
X147493Y169408D01*
X147521Y169422D01*
X147563Y169450D01*
X147632Y169492D01*
X147715Y169533D01*
X147812Y169589D01*
X148034Y169700D01*
X148312Y169811D01*
X148617Y169908D01*
X148950Y169977D01*
X149116Y170005D01*
X149421D01*
X149504Y169991D01*
X149615Y169977D01*
X149740Y169963D01*
X149879Y169935D01*
X150031Y169894D01*
X150364Y169797D01*
X150545Y169727D01*
X150725Y169630D01*
X150905Y169533D01*
X151085Y169422D01*
X151252Y169284D01*
X151418Y169131D01*
X151432Y169117D01*
X151460Y169089D01*
X151501Y169048D01*
X151557Y168979D01*
X151626Y168881D01*
X151696Y168784D01*
X151779Y168659D01*
X151862Y168521D01*
X151931Y168368D01*
X152015Y168202D01*
X152084Y168008D01*
X152153Y167813D01*
X152209Y167605D01*
X152250Y167370D01*
X152278Y167134D01*
X152292Y166884D01*
Y166870D01*
Y166829D01*
Y166759D01*
X152278Y166663D01*
X152264Y166551D01*
X152250Y166427D01*
X152223Y166274D01*
X152195Y166122D01*
X152112Y165761D01*
X151973Y165387D01*
X151890Y165192D01*
X151779Y165012D01*
X151668Y164818D01*
X151529Y164638D01*
X151515Y164624D01*
X151488Y164582D01*
X151432Y164527D01*
X151363Y164457D01*
X151266Y164374D01*
X151155Y164263D01*
X151016Y164166D01*
X150864Y164055D01*
X150697Y163944D01*
X150503Y163847D01*
X150295Y163750D01*
X150073Y163653D01*
X149837Y163584D01*
X149574Y163528D01*
X149296Y163487D01*
X149005Y163473D01*
X148880D01*
X148783Y163487D01*
X148672Y163500D01*
X148547Y163514D01*
X148395Y163528D01*
X148242Y163570D01*
X147896Y163653D01*
X147549Y163778D01*
X147369Y163861D01*
X147188Y163958D01*
X147022Y164069D01*
X146855Y164194D01*
X146842Y164208D01*
X146814Y164222D01*
X146786Y164277D01*
X146731Y164333D01*
X146661Y164402D01*
X146592Y164485D01*
X146509Y164596D01*
X146440Y164721D01*
X146356Y164846D01*
X146273Y164998D01*
X146121Y165331D01*
X145996Y165719D01*
X145954Y165927D01*
X145926Y166149D01*
X147161Y166246D01*
Y166232D01*
Y166205D01*
X147175Y166163D01*
X147188Y166094D01*
X147230Y165941D01*
X147285Y165733D01*
X147369Y165525D01*
X147480Y165289D01*
X147618Y165082D01*
X147785Y164887D01*
X147812Y164873D01*
X147868Y164818D01*
X147979Y164749D01*
X148131Y164665D01*
X148298Y164582D01*
X148506Y164513D01*
X148742Y164457D01*
X149005Y164443D01*
X149088D01*
X149144Y164457D01*
X149310Y164471D01*
X149504Y164527D01*
X149740Y164596D01*
X149976Y164707D01*
X150225Y164873D01*
X150337Y164970D01*
X150447Y165082D01*
X150461Y165095D01*
X150475Y165109D01*
X150503Y165151D01*
X150545Y165192D01*
X150642Y165345D01*
X150752Y165539D01*
X150850Y165775D01*
X150947Y166066D01*
X151016Y166413D01*
X151044Y166593D01*
Y166787D01*
Y166801D01*
Y166829D01*
Y166884D01*
X151030Y166954D01*
Y167037D01*
X151016Y167134D01*
X150974Y167356D01*
X150905Y167619D01*
X150808Y167883D01*
X150669Y168132D01*
X150475Y168368D01*
Y168382D01*
X150447Y168396D01*
X150378Y168465D01*
X150253Y168562D01*
X150087Y168673D01*
X149865Y168771D01*
X149615Y168867D01*
X149324Y168937D01*
X149158Y168965D01*
X148894D01*
X148783Y168951D01*
X148645Y168937D01*
X148478Y168895D01*
X148312Y168854D01*
X148131Y168784D01*
X147951Y168701D01*
X147937Y168687D01*
X147882Y168659D01*
X147799Y168590D01*
X147688Y168521D01*
X147577Y168424D01*
X147466Y168299D01*
X147341Y168174D01*
X147244Y168022D01*
X146134Y168174D01*
X147064Y173111D01*
X151834D01*
Y171988D01*
D02*
G37*
G36*
X105309Y176451D02*
X105434Y176437D01*
X105586Y176423D01*
X105739Y176409D01*
X105919Y176368D01*
X106293Y176285D01*
X106710Y176160D01*
X106918Y176077D01*
X107112Y175979D01*
X107306Y175855D01*
X107500Y175730D01*
X107514Y175716D01*
X107542Y175702D01*
X107597Y175660D01*
X107667Y175591D01*
X107736Y175522D01*
X107833Y175425D01*
X107930Y175314D01*
X108041Y175203D01*
X108152Y175064D01*
X108263Y174898D01*
X108388Y174731D01*
X108499Y174551D01*
X108596Y174343D01*
X108707Y174135D01*
X108790Y173913D01*
X108873Y173664D01*
X107625Y173372D01*
Y173386D01*
X107611Y173414D01*
X107583Y173469D01*
X107556Y173539D01*
X107528Y173622D01*
X107486Y173733D01*
X107375Y173955D01*
X107237Y174204D01*
X107070Y174454D01*
X106862Y174690D01*
X106640Y174898D01*
X106613Y174925D01*
X106529Y174981D01*
X106391Y175050D01*
X106210Y175147D01*
X105975Y175231D01*
X105711Y175314D01*
X105392Y175369D01*
X105045Y175383D01*
X104934D01*
X104865Y175369D01*
X104768D01*
X104657Y175355D01*
X104394Y175314D01*
X104102Y175258D01*
X103797Y175161D01*
X103478Y175023D01*
X103187Y174842D01*
X103173D01*
X103159Y174815D01*
X103062Y174745D01*
X102937Y174634D01*
X102785Y174468D01*
X102605Y174260D01*
X102438Y174024D01*
X102285Y173733D01*
X102147Y173414D01*
Y173400D01*
X102133Y173372D01*
X102119Y173331D01*
X102105Y173261D01*
X102078Y173178D01*
X102050Y173081D01*
X102008Y172845D01*
X101953Y172568D01*
X101897Y172263D01*
X101869Y171930D01*
X101856Y171569D01*
Y171556D01*
Y171514D01*
Y171444D01*
Y171361D01*
X101869Y171264D01*
Y171139D01*
X101883Y171001D01*
X101897Y170848D01*
X101939Y170515D01*
X102008Y170155D01*
X102091Y169794D01*
X102202Y169434D01*
Y169420D01*
X102216Y169392D01*
X102244Y169350D01*
X102272Y169281D01*
X102355Y169115D01*
X102480Y168920D01*
X102632Y168699D01*
X102826Y168463D01*
X103048Y168255D01*
X103312Y168061D01*
X103326D01*
X103353Y168047D01*
X103395Y168019D01*
X103450Y167991D01*
X103520Y167964D01*
X103603Y167922D01*
X103797Y167839D01*
X104047Y167756D01*
X104324Y167686D01*
X104629Y167631D01*
X104948Y167617D01*
X105045D01*
X105129Y167631D01*
X105226D01*
X105323Y167645D01*
X105572Y167700D01*
X105864Y167769D01*
X106155Y167880D01*
X106460Y168033D01*
X106613Y168116D01*
X106751Y168227D01*
X106765Y168241D01*
X106779Y168255D01*
X106820Y168296D01*
X106876Y168338D01*
X106931Y168407D01*
X107001Y168491D01*
X107084Y168574D01*
X107153Y168685D01*
X107237Y168810D01*
X107334Y168948D01*
X107417Y169087D01*
X107500Y169253D01*
X107569Y169434D01*
X107639Y169628D01*
X107708Y169836D01*
X107764Y170058D01*
X109039Y169739D01*
Y169725D01*
X109026Y169669D01*
X108998Y169586D01*
X108956Y169475D01*
X108915Y169350D01*
X108859Y169198D01*
X108790Y169031D01*
X108707Y168851D01*
X108512Y168463D01*
X108263Y168074D01*
X108110Y167880D01*
X107958Y167686D01*
X107791Y167520D01*
X107597Y167353D01*
X107583Y167339D01*
X107556Y167312D01*
X107486Y167284D01*
X107417Y167229D01*
X107306Y167159D01*
X107195Y167090D01*
X107042Y167020D01*
X106890Y166951D01*
X106710Y166868D01*
X106515Y166799D01*
X106307Y166729D01*
X106086Y166660D01*
X105850Y166604D01*
X105600Y166577D01*
X105337Y166549D01*
X105059Y166535D01*
X104907D01*
X104796Y166549D01*
X104671D01*
X104518Y166563D01*
X104352Y166591D01*
X104158Y166618D01*
X103756Y166688D01*
X103340Y166799D01*
X102923Y166951D01*
X102729Y167048D01*
X102535Y167159D01*
X102521Y167173D01*
X102494Y167187D01*
X102438Y167229D01*
X102383Y167284D01*
X102299Y167339D01*
X102202Y167423D01*
X102091Y167520D01*
X101980Y167631D01*
X101869Y167756D01*
X101745Y167880D01*
X101495Y168199D01*
X101259Y168574D01*
X101051Y168990D01*
Y169004D01*
X101024Y169045D01*
X101010Y169115D01*
X100968Y169198D01*
X100940Y169309D01*
X100899Y169447D01*
X100843Y169600D01*
X100802Y169767D01*
X100760Y169947D01*
X100704Y170155D01*
X100635Y170585D01*
X100580Y171070D01*
X100552Y171569D01*
Y171583D01*
Y171639D01*
Y171722D01*
X100566Y171819D01*
Y171958D01*
X100580Y172096D01*
X100594Y172277D01*
X100621Y172457D01*
X100691Y172859D01*
X100788Y173303D01*
X100926Y173747D01*
X101121Y174177D01*
X101135Y174191D01*
X101148Y174232D01*
X101176Y174288D01*
X101231Y174357D01*
X101287Y174454D01*
X101356Y174565D01*
X101537Y174815D01*
X101772Y175092D01*
X102050Y175369D01*
X102369Y175647D01*
X102743Y175882D01*
X102757Y175896D01*
X102799Y175910D01*
X102854Y175938D01*
X102923Y175979D01*
X103034Y176021D01*
X103145Y176063D01*
X103284Y176118D01*
X103437Y176174D01*
X103603Y176229D01*
X103783Y176285D01*
X104172Y176368D01*
X104615Y176437D01*
X105073Y176465D01*
X105212D01*
X105309Y176451D01*
D02*
G37*
G36*
X123490Y175050D02*
X119649D01*
X119136Y172457D01*
X119150Y172471D01*
X119177Y172485D01*
X119219Y172512D01*
X119288Y172554D01*
X119371Y172596D01*
X119468Y172651D01*
X119690Y172762D01*
X119968Y172873D01*
X120273Y172970D01*
X120606Y173039D01*
X120772Y173067D01*
X121077D01*
X121160Y173053D01*
X121271Y173039D01*
X121396Y173025D01*
X121535Y172998D01*
X121687Y172956D01*
X122020Y172859D01*
X122201Y172790D01*
X122381Y172693D01*
X122561Y172596D01*
X122741Y172485D01*
X122908Y172346D01*
X123074Y172193D01*
X123088Y172180D01*
X123116Y172152D01*
X123158Y172110D01*
X123213Y172041D01*
X123282Y171944D01*
X123352Y171847D01*
X123435Y171722D01*
X123518Y171583D01*
X123587Y171431D01*
X123671Y171264D01*
X123740Y171070D01*
X123809Y170876D01*
X123865Y170668D01*
X123906Y170432D01*
X123934Y170196D01*
X123948Y169947D01*
Y169933D01*
Y169891D01*
Y169822D01*
X123934Y169725D01*
X123920Y169614D01*
X123906Y169489D01*
X123879Y169336D01*
X123851Y169184D01*
X123768Y168823D01*
X123629Y168449D01*
X123546Y168255D01*
X123435Y168074D01*
X123324Y167880D01*
X123185Y167700D01*
X123171Y167686D01*
X123144Y167645D01*
X123088Y167589D01*
X123019Y167520D01*
X122922Y167437D01*
X122811Y167326D01*
X122672Y167229D01*
X122520Y167118D01*
X122353Y167007D01*
X122159Y166910D01*
X121951Y166812D01*
X121729Y166715D01*
X121493Y166646D01*
X121230Y166591D01*
X120952Y166549D01*
X120661Y166535D01*
X120536D01*
X120439Y166549D01*
X120328Y166563D01*
X120204Y166577D01*
X120051Y166591D01*
X119898Y166632D01*
X119552Y166715D01*
X119205Y166840D01*
X119025Y166923D01*
X118844Y167020D01*
X118678Y167132D01*
X118512Y167256D01*
X118498Y167270D01*
X118470Y167284D01*
X118442Y167339D01*
X118387Y167395D01*
X118317Y167464D01*
X118248Y167547D01*
X118165Y167659D01*
X118096Y167783D01*
X118012Y167908D01*
X117929Y168061D01*
X117776Y168393D01*
X117652Y168782D01*
X117610Y168990D01*
X117582Y169212D01*
X118817Y169309D01*
Y169295D01*
Y169267D01*
X118830Y169226D01*
X118844Y169156D01*
X118886Y169004D01*
X118941Y168796D01*
X119025Y168588D01*
X119136Y168352D01*
X119274Y168144D01*
X119441Y167950D01*
X119468Y167936D01*
X119524Y167880D01*
X119635Y167811D01*
X119788Y167728D01*
X119954Y167645D01*
X120162Y167575D01*
X120398Y167520D01*
X120661Y167506D01*
X120744D01*
X120800Y167520D01*
X120966Y167534D01*
X121160Y167589D01*
X121396Y167659D01*
X121632Y167769D01*
X121882Y167936D01*
X121993Y168033D01*
X122104Y168144D01*
X122117Y168158D01*
X122131Y168172D01*
X122159Y168213D01*
X122201Y168255D01*
X122298Y168407D01*
X122409Y168601D01*
X122506Y168837D01*
X122603Y169128D01*
X122672Y169475D01*
X122700Y169655D01*
Y169850D01*
Y169863D01*
Y169891D01*
Y169947D01*
X122686Y170016D01*
Y170099D01*
X122672Y170196D01*
X122631Y170418D01*
X122561Y170682D01*
X122464Y170945D01*
X122325Y171195D01*
X122131Y171431D01*
Y171444D01*
X122104Y171458D01*
X122034Y171528D01*
X121909Y171625D01*
X121743Y171736D01*
X121521Y171833D01*
X121271Y171930D01*
X120980Y171999D01*
X120814Y172027D01*
X120550D01*
X120439Y172013D01*
X120301Y171999D01*
X120134Y171958D01*
X119968Y171916D01*
X119788Y171847D01*
X119607Y171763D01*
X119593Y171750D01*
X119538Y171722D01*
X119455Y171653D01*
X119344Y171583D01*
X119233Y171486D01*
X119122Y171361D01*
X118997Y171236D01*
X118900Y171084D01*
X117790Y171236D01*
X118720Y176174D01*
X123490D01*
Y175050D01*
D02*
G37*
G36*
X114559Y166702D02*
X113380D01*
Y174204D01*
X113366Y174191D01*
X113297Y174135D01*
X113214Y174052D01*
X113075Y173955D01*
X112923Y173830D01*
X112729Y173691D01*
X112507Y173539D01*
X112257Y173386D01*
X112243D01*
X112229Y173372D01*
X112146Y173317D01*
X112007Y173247D01*
X111841Y173164D01*
X111647Y173067D01*
X111439Y172970D01*
X111231Y172873D01*
X111023Y172790D01*
Y173927D01*
X111037D01*
X111064Y173955D01*
X111120Y173969D01*
X111189Y174010D01*
X111272Y174052D01*
X111369Y174107D01*
X111605Y174246D01*
X111882Y174398D01*
X112160Y174593D01*
X112451Y174815D01*
X112742Y175050D01*
X112756Y175064D01*
X112770Y175078D01*
X112812Y175120D01*
X112867Y175161D01*
X112992Y175300D01*
X113158Y175466D01*
X113325Y175660D01*
X113505Y175882D01*
X113658Y176104D01*
X113796Y176340D01*
X114559D01*
Y166702D01*
D02*
G37*
G36*
X193571Y295894D02*
Y291831D01*
X192295D01*
Y295894D01*
X188592Y301428D01*
X190131D01*
X192017Y298515D01*
Y298501D01*
X192045Y298474D01*
X192073Y298432D01*
X192101Y298377D01*
X192156Y298307D01*
X192211Y298224D01*
X192336Y298016D01*
X192489Y297766D01*
X192655Y297489D01*
X192836Y297198D01*
X193002Y296893D01*
Y296907D01*
X193016Y296934D01*
X193044Y296976D01*
X193085Y297031D01*
X193127Y297101D01*
X193182Y297184D01*
X193307Y297392D01*
X193460Y297642D01*
X193640Y297933D01*
X193848Y298252D01*
X194070Y298598D01*
X195914Y301428D01*
X197398D01*
X193571Y295894D01*
D02*
G37*
G36*
X201476Y301455D02*
X201587Y301442D01*
X201725Y301428D01*
X201878Y301400D01*
X202030Y301372D01*
X202391Y301275D01*
X202752Y301136D01*
X202932Y301053D01*
X203112Y300956D01*
X203279Y300831D01*
X203431Y300693D01*
X203445Y300679D01*
X203473Y300665D01*
X203500Y300609D01*
X203556Y300554D01*
X203625Y300485D01*
X203695Y300388D01*
X203764Y300291D01*
X203847Y300166D01*
X203986Y299902D01*
X204125Y299569D01*
X204180Y299403D01*
X204208Y299209D01*
X204235Y299015D01*
X204249Y298807D01*
Y298779D01*
Y298710D01*
X204235Y298598D01*
X204222Y298446D01*
X204194Y298280D01*
X204138Y298085D01*
X204083Y297877D01*
X204000Y297669D01*
X203986Y297642D01*
X203958Y297572D01*
X203903Y297461D01*
X203819Y297309D01*
X203708Y297142D01*
X203570Y296934D01*
X203403Y296726D01*
X203209Y296490D01*
X203181Y296463D01*
X203112Y296380D01*
X203043Y296310D01*
X202973Y296241D01*
X202890Y296158D01*
X202779Y296047D01*
X202668Y295936D01*
X202530Y295811D01*
X202391Y295672D01*
X202225Y295520D01*
X202044Y295367D01*
X201850Y295187D01*
X201628Y295007D01*
X201406Y294813D01*
X201392Y294799D01*
X201365Y294771D01*
X201309Y294729D01*
X201240Y294674D01*
X201157Y294591D01*
X201060Y294507D01*
X200838Y294327D01*
X200602Y294119D01*
X200380Y293911D01*
X200186Y293731D01*
X200103Y293661D01*
X200033Y293592D01*
X200019Y293578D01*
X199978Y293537D01*
X199922Y293481D01*
X199853Y293398D01*
X199784Y293301D01*
X199701Y293204D01*
X199534Y292968D01*
X204263D01*
Y291831D01*
X197898D01*
Y291845D01*
Y291900D01*
Y291983D01*
X197911Y292094D01*
X197925Y292219D01*
X197953Y292358D01*
X197981Y292496D01*
X198036Y292649D01*
Y292663D01*
X198050Y292677D01*
X198078Y292760D01*
X198133Y292885D01*
X198216Y293051D01*
X198328Y293245D01*
X198466Y293467D01*
X198619Y293689D01*
X198813Y293925D01*
Y293939D01*
X198841Y293953D01*
X198910Y294036D01*
X199035Y294161D01*
X199215Y294341D01*
X199423Y294549D01*
X199687Y294799D01*
X200006Y295076D01*
X200352Y295367D01*
X200366Y295381D01*
X200422Y295423D01*
X200505Y295492D01*
X200602Y295575D01*
X200727Y295686D01*
X200879Y295811D01*
X201032Y295950D01*
X201212Y296102D01*
X201559Y296435D01*
X201905Y296768D01*
X202072Y296934D01*
X202225Y297101D01*
X202363Y297253D01*
X202474Y297406D01*
Y297420D01*
X202502Y297434D01*
X202530Y297475D01*
X202557Y297531D01*
X202654Y297683D01*
X202765Y297864D01*
X202862Y298085D01*
X202959Y298321D01*
X203015Y298585D01*
X203043Y298834D01*
Y298848D01*
Y298862D01*
X203029Y298945D01*
X203015Y299084D01*
X202973Y299237D01*
X202918Y299431D01*
X202821Y299625D01*
X202696Y299819D01*
X202530Y300013D01*
X202502Y300041D01*
X202432Y300096D01*
X202335Y300166D01*
X202183Y300263D01*
X201989Y300346D01*
X201767Y300429D01*
X201503Y300485D01*
X201212Y300499D01*
X201129D01*
X201073Y300485D01*
X200907Y300471D01*
X200713Y300429D01*
X200505Y300374D01*
X200269Y300277D01*
X200047Y300152D01*
X199839Y299985D01*
X199811Y299958D01*
X199756Y299888D01*
X199673Y299777D01*
X199590Y299611D01*
X199492Y299417D01*
X199409Y299167D01*
X199354Y298890D01*
X199326Y298571D01*
X198120Y298696D01*
Y298710D01*
X198133Y298751D01*
Y298820D01*
X198147Y298918D01*
X198175Y299028D01*
X198203Y299153D01*
X198244Y299306D01*
X198286Y299458D01*
X198397Y299791D01*
X198563Y300124D01*
X198660Y300291D01*
X198785Y300457D01*
X198910Y300609D01*
X199049Y300748D01*
X199062Y300762D01*
X199090Y300776D01*
X199132Y300818D01*
X199201Y300859D01*
X199284Y300915D01*
X199382Y300970D01*
X199492Y301039D01*
X199631Y301109D01*
X199784Y301178D01*
X199950Y301247D01*
X200130Y301303D01*
X200324Y301358D01*
X200533Y301400D01*
X200755Y301442D01*
X200990Y301455D01*
X201240Y301469D01*
X201378D01*
X201476Y301455D01*
D02*
G37*
G36*
X244650Y194841D02*
X245953D01*
Y193760D01*
X244650D01*
Y191458D01*
X243471D01*
Y193760D01*
X239296D01*
Y194841D01*
X243693Y201054D01*
X244650D01*
Y194841D01*
D02*
G37*
G36*
X235081Y201040D02*
X235205D01*
X235497Y201027D01*
X235802Y200985D01*
X236134Y200944D01*
X236440Y200874D01*
X236592Y200833D01*
X236717Y200791D01*
X236731D01*
X236745Y200777D01*
X236828Y200735D01*
X236953Y200680D01*
X237105Y200583D01*
X237272Y200458D01*
X237452Y200292D01*
X237618Y200098D01*
X237785Y199876D01*
Y199862D01*
X237799Y199848D01*
X237854Y199765D01*
X237910Y199626D01*
X237993Y199446D01*
X238062Y199238D01*
X238132Y198988D01*
X238173Y198724D01*
X238187Y198433D01*
Y198419D01*
Y198392D01*
Y198336D01*
X238173Y198267D01*
Y198170D01*
X238159Y198073D01*
X238104Y197837D01*
X238021Y197560D01*
X237910Y197268D01*
X237743Y196977D01*
X237632Y196838D01*
X237521Y196700D01*
X237507Y196686D01*
X237494Y196672D01*
X237452Y196630D01*
X237397Y196589D01*
X237327Y196533D01*
X237244Y196478D01*
X237133Y196409D01*
X237022Y196325D01*
X236883Y196256D01*
X236731Y196187D01*
X236564Y196103D01*
X236384Y196034D01*
X236176Y195979D01*
X235968Y195909D01*
X235732Y195868D01*
X235483Y195826D01*
X235510Y195812D01*
X235566Y195784D01*
X235649Y195729D01*
X235760Y195674D01*
X236010Y195521D01*
X236134Y195424D01*
X236245Y195341D01*
X236273Y195313D01*
X236343Y195244D01*
X236453Y195133D01*
X236592Y194994D01*
X236745Y194800D01*
X236925Y194592D01*
X237105Y194342D01*
X237299Y194065D01*
X238950Y191458D01*
X237369D01*
X236107Y193454D01*
Y193468D01*
X236079Y193496D01*
X236051Y193538D01*
X236010Y193593D01*
X235913Y193746D01*
X235788Y193940D01*
X235635Y194148D01*
X235483Y194370D01*
X235330Y194578D01*
X235191Y194772D01*
X235178Y194786D01*
X235136Y194841D01*
X235067Y194925D01*
X234970Y195022D01*
X234762Y195230D01*
X234651Y195327D01*
X234540Y195410D01*
X234526Y195424D01*
X234498Y195438D01*
X234443Y195465D01*
X234359Y195507D01*
X234276Y195549D01*
X234179Y195590D01*
X233957Y195660D01*
X233943D01*
X233916Y195674D01*
X233860D01*
X233791Y195687D01*
X233694Y195701D01*
X233583D01*
X233430Y195715D01*
X231794D01*
Y191458D01*
X230518D01*
Y201054D01*
X234970D01*
X235081Y201040D01*
D02*
G37*
G36*
X209611Y352883D02*
X209736Y352869D01*
X209889Y352855D01*
X210041Y352842D01*
X210222Y352800D01*
X210596Y352717D01*
X211012Y352592D01*
X211220Y352509D01*
X211414Y352412D01*
X211608Y352287D01*
X211803Y352162D01*
X211816Y352148D01*
X211844Y352134D01*
X211900Y352093D01*
X211969Y352023D01*
X212038Y351954D01*
X212135Y351857D01*
X212232Y351746D01*
X212343Y351635D01*
X212454Y351496D01*
X212565Y351330D01*
X212690Y351164D01*
X212801Y350983D01*
X212898Y350775D01*
X213009Y350567D01*
X213092Y350345D01*
X213176Y350096D01*
X211927Y349804D01*
Y349818D01*
X211913Y349846D01*
X211886Y349902D01*
X211858Y349971D01*
X211830Y350054D01*
X211789Y350165D01*
X211678Y350387D01*
X211539Y350637D01*
X211373Y350886D01*
X211165Y351122D01*
X210943Y351330D01*
X210915Y351358D01*
X210832Y351413D01*
X210693Y351483D01*
X210513Y351580D01*
X210277Y351663D01*
X210014Y351746D01*
X209694Y351801D01*
X209348Y351815D01*
X209237D01*
X209167Y351801D01*
X209070D01*
X208960Y351788D01*
X208696Y351746D01*
X208405Y351691D01*
X208100Y351594D01*
X207781Y351455D01*
X207489Y351274D01*
X207476D01*
X207462Y351247D01*
X207365Y351177D01*
X207240Y351067D01*
X207087Y350900D01*
X206907Y350692D01*
X206740Y350456D01*
X206588Y350165D01*
X206449Y349846D01*
Y349832D01*
X206435Y349804D01*
X206422Y349763D01*
X206408Y349693D01*
X206380Y349610D01*
X206352Y349513D01*
X206311Y349277D01*
X206255Y349000D01*
X206200Y348695D01*
X206172Y348362D01*
X206158Y348002D01*
Y347988D01*
Y347946D01*
Y347877D01*
Y347794D01*
X206172Y347696D01*
Y347572D01*
X206186Y347433D01*
X206200Y347280D01*
X206241Y346948D01*
X206311Y346587D01*
X206394Y346226D01*
X206505Y345866D01*
Y345852D01*
X206519Y345824D01*
X206546Y345783D01*
X206574Y345713D01*
X206657Y345547D01*
X206782Y345353D01*
X206935Y345131D01*
X207129Y344895D01*
X207351Y344687D01*
X207614Y344493D01*
X207628D01*
X207656Y344479D01*
X207698Y344451D01*
X207753Y344423D01*
X207822Y344396D01*
X207906Y344354D01*
X208100Y344271D01*
X208349Y344188D01*
X208627Y344118D01*
X208932Y344063D01*
X209251Y344049D01*
X209348D01*
X209431Y344063D01*
X209528D01*
X209625Y344077D01*
X209875Y344132D01*
X210166Y344202D01*
X210457Y344313D01*
X210762Y344465D01*
X210915Y344548D01*
X211054Y344659D01*
X211068Y344673D01*
X211081Y344687D01*
X211123Y344729D01*
X211178Y344770D01*
X211234Y344840D01*
X211303Y344923D01*
X211386Y345006D01*
X211456Y345117D01*
X211539Y345242D01*
X211636Y345380D01*
X211719Y345519D01*
X211803Y345686D01*
X211872Y345866D01*
X211941Y346060D01*
X212010Y346268D01*
X212066Y346490D01*
X213342Y346171D01*
Y346157D01*
X213328Y346102D01*
X213300Y346018D01*
X213259Y345907D01*
X213217Y345783D01*
X213162Y345630D01*
X213092Y345464D01*
X213009Y345283D01*
X212815Y344895D01*
X212565Y344507D01*
X212413Y344313D01*
X212260Y344118D01*
X212094Y343952D01*
X211900Y343786D01*
X211886Y343772D01*
X211858Y343744D01*
X211789Y343716D01*
X211719Y343661D01*
X211608Y343591D01*
X211497Y343522D01*
X211345Y343453D01*
X211192Y343383D01*
X211012Y343300D01*
X210818Y343231D01*
X210610Y343162D01*
X210388Y343092D01*
X210152Y343037D01*
X209902Y343009D01*
X209639Y342981D01*
X209362Y342967D01*
X209209D01*
X209098Y342981D01*
X208973D01*
X208821Y342995D01*
X208654Y343023D01*
X208460Y343050D01*
X208058Y343120D01*
X207642Y343231D01*
X207226Y343383D01*
X207032Y343480D01*
X206838Y343591D01*
X206824Y343605D01*
X206796Y343619D01*
X206740Y343661D01*
X206685Y343716D01*
X206602Y343772D01*
X206505Y343855D01*
X206394Y343952D01*
X206283Y344063D01*
X206172Y344188D01*
X206047Y344313D01*
X205798Y344632D01*
X205562Y345006D01*
X205354Y345422D01*
Y345436D01*
X205326Y345477D01*
X205312Y345547D01*
X205271Y345630D01*
X205243Y345741D01*
X205201Y345880D01*
X205146Y346032D01*
X205104Y346199D01*
X205063Y346379D01*
X205007Y346587D01*
X204938Y347017D01*
X204882Y347502D01*
X204854Y348002D01*
Y348015D01*
Y348071D01*
Y348154D01*
X204868Y348251D01*
Y348390D01*
X204882Y348529D01*
X204896Y348709D01*
X204924Y348889D01*
X204993Y349291D01*
X205090Y349735D01*
X205229Y350179D01*
X205423Y350609D01*
X205437Y350623D01*
X205451Y350664D01*
X205478Y350720D01*
X205534Y350789D01*
X205590Y350886D01*
X205659Y350997D01*
X205839Y351247D01*
X206075Y351524D01*
X206352Y351801D01*
X206671Y352079D01*
X207046Y352315D01*
X207059Y352328D01*
X207101Y352342D01*
X207157Y352370D01*
X207226Y352412D01*
X207337Y352453D01*
X207448Y352495D01*
X207586Y352550D01*
X207739Y352606D01*
X207906Y352661D01*
X208086Y352717D01*
X208474Y352800D01*
X208918Y352869D01*
X209375Y352897D01*
X209514D01*
X209611Y352883D01*
D02*
G37*
G36*
X218862Y343134D02*
X217683D01*
Y350637D01*
X217669Y350623D01*
X217600Y350567D01*
X217516Y350484D01*
X217378Y350387D01*
X217225Y350262D01*
X217031Y350123D01*
X216809Y349971D01*
X216559Y349818D01*
X216546D01*
X216532Y349804D01*
X216448Y349749D01*
X216310Y349680D01*
X216143Y349596D01*
X215949Y349499D01*
X215741Y349402D01*
X215533Y349305D01*
X215325Y349222D01*
Y350359D01*
X215339D01*
X215367Y350387D01*
X215422Y350401D01*
X215492Y350442D01*
X215575Y350484D01*
X215672Y350540D01*
X215907Y350678D01*
X216185Y350831D01*
X216462Y351025D01*
X216754Y351247D01*
X217045Y351483D01*
X217059Y351496D01*
X217073Y351510D01*
X217114Y351552D01*
X217170Y351594D01*
X217294Y351732D01*
X217461Y351899D01*
X217627Y352093D01*
X217808Y352315D01*
X217960Y352537D01*
X218099Y352772D01*
X218862D01*
Y343134D01*
D02*
G37*
G36*
X225296Y352758D02*
X225477Y352731D01*
X225685Y352689D01*
X225907Y352634D01*
X226142Y352564D01*
X226364Y352453D01*
X226378D01*
X226392Y352439D01*
X226461Y352398D01*
X226572Y352328D01*
X226711Y352231D01*
X226864Y352093D01*
X227030Y351940D01*
X227183Y351760D01*
X227335Y351552D01*
X227349Y351524D01*
X227404Y351455D01*
X227460Y351330D01*
X227557Y351150D01*
X227640Y350942D01*
X227751Y350706D01*
X227848Y350429D01*
X227931Y350123D01*
Y350110D01*
X227945Y350082D01*
X227959Y350040D01*
X227973Y349971D01*
X227987Y349888D01*
X228001Y349791D01*
X228029Y349666D01*
X228042Y349527D01*
X228070Y349375D01*
X228084Y349208D01*
X228098Y349014D01*
X228126Y348820D01*
X228139Y348598D01*
Y348376D01*
X228153Y348126D01*
Y347863D01*
Y347849D01*
Y347794D01*
Y347696D01*
Y347585D01*
X228139Y347433D01*
Y347267D01*
X228126Y347086D01*
X228112Y346892D01*
X228070Y346448D01*
X228001Y345991D01*
X227918Y345547D01*
X227862Y345339D01*
X227793Y345131D01*
Y345117D01*
X227779Y345089D01*
X227751Y345034D01*
X227723Y344964D01*
X227696Y344867D01*
X227640Y344770D01*
X227529Y344534D01*
X227391Y344285D01*
X227210Y344007D01*
X227002Y343758D01*
X226753Y343522D01*
X226739D01*
X226725Y343494D01*
X226683Y343467D01*
X226628Y343439D01*
X226558Y343397D01*
X226489Y343342D01*
X226281Y343245D01*
X226031Y343148D01*
X225740Y343050D01*
X225394Y342995D01*
X225019Y342967D01*
X224880D01*
X224783Y342981D01*
X224672Y342995D01*
X224534Y343023D01*
X224381Y343050D01*
X224215Y343092D01*
X224048Y343148D01*
X223868Y343203D01*
X223688Y343286D01*
X223507Y343383D01*
X223327Y343494D01*
X223147Y343633D01*
X222980Y343786D01*
X222828Y343952D01*
X222814Y343966D01*
X222786Y344007D01*
X222745Y344077D01*
X222675Y344188D01*
X222606Y344313D01*
X222537Y344479D01*
X222440Y344673D01*
X222356Y344895D01*
X222273Y345145D01*
X222190Y345436D01*
X222107Y345755D01*
X222037Y346115D01*
X221968Y346504D01*
X221926Y346920D01*
X221899Y347378D01*
X221885Y347863D01*
Y347877D01*
Y347932D01*
Y348029D01*
Y348140D01*
X221899Y348293D01*
Y348459D01*
X221913Y348639D01*
X221926Y348848D01*
X221968Y349277D01*
X222037Y349735D01*
X222121Y350193D01*
X222176Y350401D01*
X222232Y350609D01*
Y350623D01*
X222245Y350650D01*
X222273Y350706D01*
X222301Y350775D01*
X222329Y350872D01*
X222384Y350969D01*
X222495Y351205D01*
X222634Y351455D01*
X222814Y351718D01*
X223022Y351982D01*
X223272Y352204D01*
X223286D01*
X223299Y352231D01*
X223341Y352259D01*
X223396Y352287D01*
X223466Y352342D01*
X223549Y352384D01*
X223757Y352495D01*
X224007Y352592D01*
X224298Y352689D01*
X224645Y352745D01*
X225019Y352772D01*
X225144D01*
X225296Y352758D01*
D02*
G37*
G36*
X210317Y340815D02*
X210442Y340801D01*
X210595Y340787D01*
X210747Y340773D01*
X210927Y340731D01*
X211302Y340648D01*
X211718Y340523D01*
X211926Y340440D01*
X212120Y340343D01*
X212314Y340218D01*
X212508Y340093D01*
X212522Y340080D01*
X212550Y340066D01*
X212605Y340024D01*
X212675Y339955D01*
X212744Y339885D01*
X212841Y339788D01*
X212938Y339677D01*
X213049Y339566D01*
X213160Y339428D01*
X213271Y339261D01*
X213396Y339095D01*
X213507Y338915D01*
X213604Y338707D01*
X213715Y338499D01*
X213798Y338277D01*
X213881Y338027D01*
X212633Y337736D01*
Y337750D01*
X212619Y337777D01*
X212592Y337833D01*
X212564Y337902D01*
X212536Y337985D01*
X212495Y338096D01*
X212384Y338318D01*
X212245Y338568D01*
X212078Y338818D01*
X211870Y339053D01*
X211649Y339261D01*
X211621Y339289D01*
X211538Y339345D01*
X211399Y339414D01*
X211219Y339511D01*
X210983Y339594D01*
X210719Y339677D01*
X210400Y339733D01*
X210054Y339747D01*
X209943D01*
X209873Y339733D01*
X209776D01*
X209665Y339719D01*
X209402Y339677D01*
X209111Y339622D01*
X208806Y339525D01*
X208487Y339386D01*
X208195Y339206D01*
X208181D01*
X208168Y339178D01*
X208071Y339109D01*
X207946Y338998D01*
X207793Y338831D01*
X207613Y338623D01*
X207446Y338388D01*
X207294Y338096D01*
X207155Y337777D01*
Y337764D01*
X207141Y337736D01*
X207127Y337694D01*
X207114Y337625D01*
X207086Y337542D01*
X207058Y337445D01*
X207017Y337209D01*
X206961Y336931D01*
X206906Y336626D01*
X206878Y336293D01*
X206864Y335933D01*
Y335919D01*
Y335877D01*
Y335808D01*
Y335725D01*
X206878Y335628D01*
Y335503D01*
X206892Y335364D01*
X206906Y335212D01*
X206947Y334879D01*
X207017Y334518D01*
X207100Y334158D01*
X207211Y333797D01*
Y333783D01*
X207225Y333756D01*
X207252Y333714D01*
X207280Y333645D01*
X207363Y333478D01*
X207488Y333284D01*
X207641Y333062D01*
X207835Y332826D01*
X208057Y332618D01*
X208320Y332424D01*
X208334D01*
X208362Y332410D01*
X208403Y332383D01*
X208459Y332355D01*
X208528Y332327D01*
X208611Y332286D01*
X208806Y332202D01*
X209055Y332119D01*
X209333Y332050D01*
X209638Y331994D01*
X209957Y331981D01*
X210054D01*
X210137Y331994D01*
X210234D01*
X210331Y332008D01*
X210581Y332064D01*
X210872Y332133D01*
X211163Y332244D01*
X211468Y332397D01*
X211621Y332480D01*
X211759Y332591D01*
X211773Y332604D01*
X211787Y332618D01*
X211829Y332660D01*
X211884Y332702D01*
X211940Y332771D01*
X212009Y332854D01*
X212092Y332937D01*
X212162Y333048D01*
X212245Y333173D01*
X212342Y333312D01*
X212425Y333451D01*
X212508Y333617D01*
X212578Y333797D01*
X212647Y333991D01*
X212717Y334199D01*
X212772Y334421D01*
X214048Y334102D01*
Y334089D01*
X214034Y334033D01*
X214006Y333950D01*
X213965Y333839D01*
X213923Y333714D01*
X213867Y333562D01*
X213798Y333395D01*
X213715Y333215D01*
X213521Y332826D01*
X213271Y332438D01*
X213119Y332244D01*
X212966Y332050D01*
X212800Y331883D01*
X212605Y331717D01*
X212592Y331703D01*
X212564Y331675D01*
X212495Y331648D01*
X212425Y331592D01*
X212314Y331523D01*
X212203Y331454D01*
X212051Y331384D01*
X211898Y331315D01*
X211718Y331232D01*
X211524Y331162D01*
X211316Y331093D01*
X211094Y331023D01*
X210858Y330968D01*
X210609Y330940D01*
X210345Y330913D01*
X210068Y330899D01*
X209915D01*
X209804Y330913D01*
X209679D01*
X209527Y330927D01*
X209360Y330954D01*
X209166Y330982D01*
X208764Y331051D01*
X208348Y331162D01*
X207932Y331315D01*
X207738Y331412D01*
X207544Y331523D01*
X207530Y331537D01*
X207502Y331550D01*
X207446Y331592D01*
X207391Y331648D01*
X207308Y331703D01*
X207211Y331786D01*
X207100Y331883D01*
X206989Y331994D01*
X206878Y332119D01*
X206753Y332244D01*
X206503Y332563D01*
X206268Y332937D01*
X206060Y333353D01*
Y333367D01*
X206032Y333409D01*
X206018Y333478D01*
X205976Y333562D01*
X205949Y333672D01*
X205907Y333811D01*
X205852Y333964D01*
X205810Y334130D01*
X205768Y334310D01*
X205713Y334518D01*
X205644Y334948D01*
X205588Y335434D01*
X205560Y335933D01*
Y335947D01*
Y336002D01*
Y336086D01*
X205574Y336183D01*
Y336321D01*
X205588Y336460D01*
X205602Y336640D01*
X205630Y336820D01*
X205699Y337223D01*
X205796Y337667D01*
X205935Y338110D01*
X206129Y338540D01*
X206143Y338554D01*
X206157Y338596D01*
X206184Y338651D01*
X206240Y338721D01*
X206295Y338818D01*
X206365Y338928D01*
X206545Y339178D01*
X206781Y339455D01*
X207058Y339733D01*
X207377Y340010D01*
X207752Y340246D01*
X207765Y340260D01*
X207807Y340274D01*
X207862Y340302D01*
X207932Y340343D01*
X208043Y340385D01*
X208154Y340426D01*
X208292Y340482D01*
X208445Y340537D01*
X208611Y340593D01*
X208792Y340648D01*
X209180Y340731D01*
X209624Y340801D01*
X210082Y340829D01*
X210220D01*
X210317Y340815D01*
D02*
G37*
G36*
X218305Y340690D02*
X218375D01*
X218472Y340676D01*
X218708Y340634D01*
X218971Y340579D01*
X219262Y340482D01*
X219554Y340357D01*
X219845Y340191D01*
X219859D01*
X219873Y340163D01*
X219914Y340135D01*
X219970Y340093D01*
X220108Y339982D01*
X220289Y339830D01*
X220469Y339622D01*
X220677Y339372D01*
X220857Y339081D01*
X221024Y338748D01*
Y338734D01*
X221038Y338707D01*
X221065Y338651D01*
X221093Y338582D01*
X221121Y338485D01*
X221162Y338360D01*
X221190Y338221D01*
X221232Y338069D01*
X221273Y337888D01*
X221315Y337680D01*
X221343Y337458D01*
X221370Y337223D01*
X221398Y336959D01*
X221426Y336682D01*
X221440Y336377D01*
Y336058D01*
Y336044D01*
Y335975D01*
Y335877D01*
Y335753D01*
X221426Y335600D01*
Y335420D01*
X221412Y335212D01*
X221384Y335004D01*
X221343Y334532D01*
X221273Y334033D01*
X221176Y333562D01*
X221107Y333326D01*
X221038Y333118D01*
Y333104D01*
X221024Y333076D01*
X220996Y333021D01*
X220968Y332937D01*
X220927Y332854D01*
X220871Y332743D01*
X220732Y332508D01*
X220566Y332244D01*
X220372Y331967D01*
X220122Y331703D01*
X219845Y331467D01*
X219831D01*
X219803Y331440D01*
X219762Y331412D01*
X219706Y331384D01*
X219623Y331343D01*
X219540Y331287D01*
X219429Y331232D01*
X219318Y331190D01*
X219054Y331079D01*
X218735Y330982D01*
X218389Y330927D01*
X218000Y330899D01*
X217889D01*
X217820Y330913D01*
X217723D01*
X217612Y330927D01*
X217348Y330982D01*
X217057Y331051D01*
X216752Y331162D01*
X216447Y331315D01*
X216294Y331412D01*
X216156Y331523D01*
X216142Y331537D01*
X216128Y331550D01*
X216087Y331592D01*
X216045Y331634D01*
X215989Y331703D01*
X215920Y331786D01*
X215781Y331981D01*
X215643Y332230D01*
X215504Y332535D01*
X215393Y332882D01*
X215310Y333284D01*
X216447Y333381D01*
Y333367D01*
X216461Y333340D01*
Y333312D01*
X216475Y333256D01*
X216516Y333104D01*
X216572Y332937D01*
X216641Y332743D01*
X216738Y332549D01*
X216849Y332369D01*
X216988Y332216D01*
X217002Y332202D01*
X217057Y332161D01*
X217154Y332105D01*
X217265Y332050D01*
X217418Y331981D01*
X217598Y331925D01*
X217806Y331883D01*
X218028Y331870D01*
X218125D01*
X218222Y331883D01*
X218347Y331897D01*
X218500Y331925D01*
X218652Y331967D01*
X218819Y332022D01*
X218971Y332105D01*
X218985Y332119D01*
X219041Y332147D01*
X219124Y332202D01*
X219207Y332286D01*
X219318Y332383D01*
X219429Y332494D01*
X219540Y332618D01*
X219651Y332771D01*
X219664Y332785D01*
X219692Y332854D01*
X219748Y332951D01*
X219803Y333076D01*
X219873Y333242D01*
X219942Y333437D01*
X220011Y333658D01*
X220081Y333908D01*
Y333922D01*
X220095Y333936D01*
Y333978D01*
X220108Y334033D01*
X220136Y334172D01*
X220178Y334352D01*
X220205Y334574D01*
X220233Y334810D01*
X220247Y335073D01*
X220261Y335350D01*
Y335364D01*
Y335406D01*
Y335475D01*
Y335586D01*
X220247Y335559D01*
X220191Y335489D01*
X220108Y335392D01*
X220011Y335253D01*
X219873Y335115D01*
X219706Y334962D01*
X219512Y334810D01*
X219290Y334671D01*
X219262Y334657D01*
X219179Y334616D01*
X219054Y334560D01*
X218902Y334505D01*
X218694Y334435D01*
X218472Y334380D01*
X218222Y334338D01*
X217959Y334324D01*
X217848D01*
X217765Y334338D01*
X217654Y334352D01*
X217543Y334366D01*
X217404Y334394D01*
X217265Y334435D01*
X216946Y334532D01*
X216780Y334602D01*
X216614Y334685D01*
X216433Y334782D01*
X216267Y334907D01*
X216100Y335032D01*
X215948Y335184D01*
X215934Y335198D01*
X215906Y335226D01*
X215879Y335267D01*
X215823Y335337D01*
X215754Y335434D01*
X215684Y335531D01*
X215615Y335656D01*
X215546Y335794D01*
X215462Y335947D01*
X215393Y336113D01*
X215324Y336307D01*
X215254Y336502D01*
X215199Y336724D01*
X215171Y336959D01*
X215143Y337195D01*
X215130Y337458D01*
Y337472D01*
Y337528D01*
Y337597D01*
X215143Y337694D01*
X215157Y337819D01*
X215171Y337972D01*
X215199Y338124D01*
X215240Y338304D01*
X215338Y338665D01*
X215407Y338859D01*
X215490Y339067D01*
X215587Y339261D01*
X215712Y339442D01*
X215837Y339636D01*
X215989Y339802D01*
X216003Y339816D01*
X216031Y339844D01*
X216073Y339885D01*
X216142Y339941D01*
X216225Y340010D01*
X216336Y340093D01*
X216447Y340163D01*
X216586Y340260D01*
X216724Y340343D01*
X216891Y340412D01*
X217265Y340565D01*
X217460Y340620D01*
X217681Y340662D01*
X217903Y340690D01*
X218139Y340704D01*
X218236D01*
X218305Y340690D01*
D02*
G37*
G36*
X440019Y392669D02*
X440047Y392641D01*
X440103Y392586D01*
X440186Y392530D01*
X440283Y392447D01*
X440394Y392336D01*
X440532Y392225D01*
X440699Y392100D01*
X440865Y391975D01*
X441059Y391823D01*
X441281Y391670D01*
X441503Y391518D01*
X441753Y391351D01*
X442016Y391185D01*
X442308Y391018D01*
X442599Y390852D01*
X442613Y390838D01*
X442668Y390811D01*
X442752Y390769D01*
X442876Y390700D01*
X443029Y390630D01*
X443195Y390547D01*
X443389Y390450D01*
X443611Y390353D01*
X443861Y390242D01*
X444111Y390117D01*
X444388Y390006D01*
X444679Y389895D01*
X445275Y389673D01*
X445914Y389465D01*
X445927D01*
X445969Y389451D01*
X446038Y389437D01*
X446121Y389410D01*
X446232Y389382D01*
X446371Y389354D01*
X446524Y389313D01*
X446690Y389285D01*
X446884Y389243D01*
X447092Y389202D01*
X447536Y389132D01*
X448022Y389063D01*
X448549Y389021D01*
Y387815D01*
X448535D01*
X448493D01*
X448438D01*
X448354Y387829D01*
X448243D01*
X448105Y387843D01*
X447952Y387856D01*
X447786Y387870D01*
X447592Y387898D01*
X447397Y387926D01*
X447162Y387967D01*
X446926Y388009D01*
X446676Y388051D01*
X446399Y388106D01*
X445830Y388245D01*
X445816D01*
X445761Y388259D01*
X445678Y388286D01*
X445553Y388328D01*
X445414Y388370D01*
X445248Y388425D01*
X445054Y388481D01*
X444846Y388564D01*
X444610Y388647D01*
X444374Y388730D01*
X443847Y388938D01*
X443292Y389188D01*
X442738Y389465D01*
X442724Y389479D01*
X442668Y389507D01*
X442599Y389548D01*
X442488Y389604D01*
X442363Y389673D01*
X442211Y389770D01*
X442044Y389867D01*
X441864Y389978D01*
X441462Y390242D01*
X441046Y390519D01*
X440616Y390838D01*
X440214Y391171D01*
Y386470D01*
X439076D01*
Y392683D01*
X440005D01*
X440019Y392669D01*
D02*
G37*
G36*
X445581Y385291D02*
X445664Y385263D01*
X445775Y385221D01*
X445900Y385180D01*
X446052Y385125D01*
X446219Y385055D01*
X446399Y384972D01*
X446787Y384778D01*
X447175Y384528D01*
X447370Y384376D01*
X447564Y384223D01*
X447730Y384057D01*
X447897Y383862D01*
X447910Y383849D01*
X447938Y383821D01*
X447966Y383751D01*
X448022Y383682D01*
X448091Y383571D01*
X448160Y383460D01*
X448229Y383308D01*
X448299Y383155D01*
X448382Y382975D01*
X448451Y382781D01*
X448521Y382573D01*
X448590Y382351D01*
X448646Y382115D01*
X448673Y381865D01*
X448701Y381602D01*
X448715Y381325D01*
Y381172D01*
X448701Y381061D01*
Y380936D01*
X448687Y380784D01*
X448659Y380617D01*
X448632Y380423D01*
X448562Y380021D01*
X448451Y379605D01*
X448299Y379189D01*
X448202Y378995D01*
X448091Y378801D01*
X448077Y378787D01*
X448063Y378759D01*
X448022Y378703D01*
X447966Y378648D01*
X447910Y378565D01*
X447827Y378468D01*
X447730Y378357D01*
X447619Y378246D01*
X447495Y378135D01*
X447370Y378010D01*
X447051Y377760D01*
X446676Y377525D01*
X446260Y377317D01*
X446246D01*
X446205Y377289D01*
X446135Y377275D01*
X446052Y377233D01*
X445941Y377206D01*
X445802Y377164D01*
X445650Y377108D01*
X445484Y377067D01*
X445303Y377025D01*
X445095Y376970D01*
X444665Y376900D01*
X444180Y376845D01*
X443681Y376817D01*
X443667D01*
X443611D01*
X443528D01*
X443431Y376831D01*
X443292D01*
X443154Y376845D01*
X442973Y376859D01*
X442793Y376887D01*
X442391Y376956D01*
X441947Y377053D01*
X441503Y377192D01*
X441073Y377386D01*
X441059Y377400D01*
X441018Y377414D01*
X440962Y377441D01*
X440893Y377497D01*
X440796Y377552D01*
X440685Y377622D01*
X440435Y377802D01*
X440158Y378038D01*
X439881Y378315D01*
X439603Y378634D01*
X439368Y379008D01*
X439354Y379022D01*
X439340Y379064D01*
X439312Y379119D01*
X439271Y379189D01*
X439229Y379300D01*
X439187Y379411D01*
X439132Y379549D01*
X439076Y379702D01*
X439021Y379868D01*
X438965Y380049D01*
X438882Y380437D01*
X438813Y380881D01*
X438785Y381338D01*
Y381477D01*
X438799Y381574D01*
X438813Y381699D01*
X438827Y381852D01*
X438841Y382004D01*
X438882Y382184D01*
X438965Y382559D01*
X439090Y382975D01*
X439173Y383183D01*
X439271Y383377D01*
X439395Y383571D01*
X439520Y383765D01*
X439534Y383779D01*
X439548Y383807D01*
X439590Y383862D01*
X439659Y383932D01*
X439728Y384001D01*
X439825Y384098D01*
X439936Y384195D01*
X440047Y384306D01*
X440186Y384417D01*
X440352Y384528D01*
X440519Y384653D01*
X440699Y384764D01*
X440907Y384861D01*
X441115Y384972D01*
X441337Y385055D01*
X441586Y385138D01*
X441878Y383890D01*
X441864D01*
X441836Y383876D01*
X441781Y383849D01*
X441711Y383821D01*
X441628Y383793D01*
X441517Y383751D01*
X441295Y383641D01*
X441046Y383502D01*
X440796Y383335D01*
X440560Y383127D01*
X440352Y382906D01*
X440325Y382878D01*
X440269Y382795D01*
X440200Y382656D01*
X440103Y382476D01*
X440019Y382240D01*
X439936Y381976D01*
X439881Y381657D01*
X439867Y381311D01*
Y381200D01*
X439881Y381130D01*
Y381033D01*
X439895Y380922D01*
X439936Y380659D01*
X439992Y380368D01*
X440089Y380062D01*
X440227Y379743D01*
X440408Y379452D01*
Y379438D01*
X440435Y379425D01*
X440505Y379328D01*
X440616Y379203D01*
X440782Y379050D01*
X440990Y378870D01*
X441226Y378703D01*
X441517Y378551D01*
X441836Y378412D01*
X441850D01*
X441878Y378398D01*
X441919Y378384D01*
X441989Y378371D01*
X442072Y378343D01*
X442169Y378315D01*
X442405Y378274D01*
X442682Y378218D01*
X442987Y378162D01*
X443320Y378135D01*
X443681Y378121D01*
X443694D01*
X443736D01*
X443806D01*
X443889D01*
X443986Y378135D01*
X444111D01*
X444249Y378149D01*
X444402Y378162D01*
X444735Y378204D01*
X445095Y378274D01*
X445456Y378357D01*
X445816Y378468D01*
X445830D01*
X445858Y378481D01*
X445900Y378509D01*
X445969Y378537D01*
X446135Y378620D01*
X446329Y378745D01*
X446551Y378898D01*
X446787Y379092D01*
X446995Y379314D01*
X447189Y379577D01*
Y379591D01*
X447203Y379619D01*
X447231Y379660D01*
X447259Y379716D01*
X447286Y379785D01*
X447328Y379868D01*
X447411Y380062D01*
X447495Y380312D01*
X447564Y380589D01*
X447619Y380895D01*
X447633Y381214D01*
Y381311D01*
X447619Y381394D01*
Y381491D01*
X447605Y381588D01*
X447550Y381838D01*
X447481Y382129D01*
X447370Y382420D01*
X447217Y382725D01*
X447134Y382878D01*
X447023Y383017D01*
X447009Y383030D01*
X446995Y383044D01*
X446954Y383086D01*
X446912Y383141D01*
X446843Y383197D01*
X446759Y383266D01*
X446676Y383349D01*
X446565Y383419D01*
X446441Y383502D01*
X446302Y383599D01*
X446163Y383682D01*
X445997Y383765D01*
X445816Y383835D01*
X445622Y383904D01*
X445414Y383973D01*
X445192Y384029D01*
X445511Y385305D01*
X445525D01*
X445581Y385291D01*
D02*
G37*
G36*
X199986Y416494D02*
Y412431D01*
X198710D01*
Y416494D01*
X195007Y422028D01*
X196547D01*
X198433Y419115D01*
Y419101D01*
X198461Y419074D01*
X198489Y419032D01*
X198516Y418977D01*
X198572Y418907D01*
X198627Y418824D01*
X198752Y418616D01*
X198904Y418366D01*
X199071Y418089D01*
X199251Y417798D01*
X199418Y417493D01*
Y417507D01*
X199431Y417534D01*
X199459Y417576D01*
X199501Y417631D01*
X199543Y417701D01*
X199598Y417784D01*
X199723Y417992D01*
X199875Y418242D01*
X200056Y418533D01*
X200264Y418852D01*
X200485Y419198D01*
X202330Y422028D01*
X203814D01*
X199986Y416494D01*
D02*
G37*
G36*
X208918Y412431D02*
X207739D01*
Y419934D01*
X207725Y419920D01*
X207656Y419864D01*
X207572Y419781D01*
X207434Y419684D01*
X207281Y419559D01*
X207087Y419420D01*
X206865Y419268D01*
X206615Y419115D01*
X206602D01*
X206588Y419101D01*
X206504Y419046D01*
X206366Y418977D01*
X206199Y418893D01*
X206005Y418796D01*
X205797Y418699D01*
X205589Y418602D01*
X205381Y418519D01*
Y419656D01*
X205395D01*
X205423Y419684D01*
X205478Y419698D01*
X205548Y419739D01*
X205631Y419781D01*
X205728Y419836D01*
X205963Y419975D01*
X206241Y420128D01*
X206518Y420322D01*
X206810Y420544D01*
X207101Y420779D01*
X207115Y420793D01*
X207129Y420807D01*
X207170Y420849D01*
X207225Y420890D01*
X207350Y421029D01*
X207517Y421196D01*
X207683Y421390D01*
X207864Y421612D01*
X208016Y421833D01*
X208155Y422069D01*
X208918D01*
Y412431D01*
D02*
G37*
G36*
X19064Y124881D02*
X11561D01*
X11575Y124867D01*
X11630Y124797D01*
X11714Y124714D01*
X11811Y124575D01*
X11935Y124423D01*
X12074Y124229D01*
X12227Y124007D01*
X12379Y123757D01*
Y123743D01*
X12393Y123729D01*
X12449Y123646D01*
X12518Y123508D01*
X12601Y123341D01*
X12698Y123147D01*
X12795Y122939D01*
X12892Y122731D01*
X12976Y122523D01*
X11838D01*
Y122537D01*
X11811Y122564D01*
X11797Y122620D01*
X11755Y122689D01*
X11714Y122773D01*
X11658Y122870D01*
X11520Y123105D01*
X11367Y123383D01*
X11173Y123660D01*
X10951Y123951D01*
X10715Y124243D01*
X10701Y124256D01*
X10687Y124270D01*
X10646Y124312D01*
X10604Y124367D01*
X10466Y124492D01*
X10299Y124659D01*
X10105Y124825D01*
X9883Y125005D01*
X9661Y125158D01*
X9425Y125297D01*
Y126059D01*
X19064D01*
Y124881D01*
D02*
G37*
G36*
Y119292D02*
X17067Y118030D01*
X17053D01*
X17025Y118002D01*
X16984Y117974D01*
X16928Y117933D01*
X16776Y117835D01*
X16581Y117711D01*
X16373Y117558D01*
X16151Y117406D01*
X15943Y117253D01*
X15749Y117114D01*
X15735Y117100D01*
X15680Y117059D01*
X15597Y116989D01*
X15500Y116892D01*
X15292Y116684D01*
X15195Y116573D01*
X15111Y116462D01*
X15098Y116449D01*
X15084Y116421D01*
X15056Y116365D01*
X15014Y116282D01*
X14973Y116199D01*
X14931Y116102D01*
X14862Y115880D01*
Y115866D01*
X14848Y115838D01*
Y115783D01*
X14834Y115714D01*
X14820Y115617D01*
Y115506D01*
X14806Y115353D01*
Y113716D01*
X19064D01*
Y112441D01*
X9467D01*
Y116892D01*
X9481Y117003D01*
Y117128D01*
X9495Y117419D01*
X9536Y117725D01*
X9578Y118057D01*
X9647Y118362D01*
X9689Y118515D01*
X9730Y118640D01*
Y118654D01*
X9744Y118667D01*
X9786Y118751D01*
X9841Y118876D01*
X9938Y119028D01*
X10063Y119194D01*
X10230Y119375D01*
X10424Y119541D01*
X10646Y119708D01*
X10660D01*
X10674Y119721D01*
X10757Y119777D01*
X10895Y119832D01*
X11076Y119916D01*
X11284Y119985D01*
X11533Y120054D01*
X11797Y120096D01*
X12088Y120110D01*
X12102D01*
X12130D01*
X12185D01*
X12255Y120096D01*
X12352D01*
X12449Y120082D01*
X12684Y120027D01*
X12962Y119943D01*
X13253Y119832D01*
X13544Y119666D01*
X13683Y119555D01*
X13822Y119444D01*
X13836Y119430D01*
X13849Y119416D01*
X13891Y119375D01*
X13933Y119319D01*
X13988Y119250D01*
X14044Y119167D01*
X14113Y119056D01*
X14196Y118945D01*
X14265Y118806D01*
X14335Y118654D01*
X14418Y118487D01*
X14487Y118307D01*
X14543Y118099D01*
X14612Y117891D01*
X14654Y117655D01*
X14695Y117406D01*
X14709Y117433D01*
X14737Y117489D01*
X14792Y117572D01*
X14848Y117683D01*
X15000Y117933D01*
X15098Y118057D01*
X15181Y118168D01*
X15208Y118196D01*
X15278Y118265D01*
X15389Y118376D01*
X15527Y118515D01*
X15722Y118667D01*
X15930Y118848D01*
X16179Y119028D01*
X16457Y119222D01*
X19064Y120873D01*
Y119292D01*
D02*
G37*
G36*
X89941Y193139D02*
X90010D01*
X90107Y193125D01*
X90343Y193083D01*
X90606Y193028D01*
X90898Y192931D01*
X91189Y192806D01*
X91480Y192639D01*
X91494D01*
X91508Y192612D01*
X91549Y192584D01*
X91605Y192542D01*
X91743Y192431D01*
X91924Y192279D01*
X92104Y192071D01*
X92312Y191821D01*
X92492Y191530D01*
X92659Y191197D01*
Y191183D01*
X92673Y191155D01*
X92700Y191100D01*
X92728Y191031D01*
X92756Y190933D01*
X92797Y190809D01*
X92825Y190670D01*
X92867Y190518D01*
X92908Y190337D01*
X92950Y190129D01*
X92978Y189907D01*
X93006Y189671D01*
X93033Y189408D01*
X93061Y189131D01*
X93075Y188825D01*
Y188507D01*
Y188493D01*
Y188423D01*
Y188326D01*
Y188202D01*
X93061Y188049D01*
Y187869D01*
X93047Y187661D01*
X93019Y187453D01*
X92978Y186981D01*
X92908Y186482D01*
X92811Y186010D01*
X92742Y185774D01*
X92673Y185567D01*
Y185553D01*
X92659Y185525D01*
X92631Y185469D01*
X92603Y185386D01*
X92562Y185303D01*
X92506Y185192D01*
X92368Y184956D01*
X92201Y184693D01*
X92007Y184415D01*
X91757Y184152D01*
X91480Y183916D01*
X91466D01*
X91438Y183888D01*
X91397Y183861D01*
X91341Y183833D01*
X91258Y183791D01*
X91175Y183736D01*
X91064Y183680D01*
X90953Y183639D01*
X90689Y183528D01*
X90371Y183431D01*
X90024Y183375D01*
X89635Y183347D01*
X89525D01*
X89455Y183361D01*
X89358D01*
X89247Y183375D01*
X88984Y183431D01*
X88693Y183500D01*
X88387Y183611D01*
X88082Y183764D01*
X87930Y183861D01*
X87791Y183972D01*
X87777Y183986D01*
X87763Y183999D01*
X87722Y184041D01*
X87680Y184083D01*
X87625Y184152D01*
X87555Y184235D01*
X87417Y184429D01*
X87278Y184679D01*
X87139Y184984D01*
X87028Y185331D01*
X86945Y185733D01*
X88082Y185830D01*
Y185816D01*
X88096Y185788D01*
Y185761D01*
X88110Y185705D01*
X88152Y185553D01*
X88207Y185386D01*
X88276Y185192D01*
X88373Y184998D01*
X88484Y184818D01*
X88623Y184665D01*
X88637Y184651D01*
X88693Y184610D01*
X88790Y184554D01*
X88900Y184499D01*
X89053Y184429D01*
X89233Y184374D01*
X89441Y184332D01*
X89663Y184318D01*
X89760D01*
X89857Y184332D01*
X89982Y184346D01*
X90135Y184374D01*
X90287Y184415D01*
X90454Y184471D01*
X90606Y184554D01*
X90620Y184568D01*
X90676Y184596D01*
X90759Y184651D01*
X90842Y184734D01*
X90953Y184831D01*
X91064Y184942D01*
X91175Y185067D01*
X91286Y185220D01*
X91300Y185234D01*
X91327Y185303D01*
X91383Y185400D01*
X91438Y185525D01*
X91508Y185691D01*
X91577Y185885D01*
X91646Y186107D01*
X91716Y186357D01*
Y186371D01*
X91730Y186385D01*
Y186426D01*
X91743Y186482D01*
X91771Y186621D01*
X91813Y186801D01*
X91841Y187023D01*
X91868Y187258D01*
X91882Y187522D01*
X91896Y187799D01*
Y187813D01*
Y187855D01*
Y187924D01*
Y188035D01*
X91882Y188007D01*
X91827Y187938D01*
X91743Y187841D01*
X91646Y187702D01*
X91508Y187563D01*
X91341Y187411D01*
X91147Y187258D01*
X90925Y187120D01*
X90898Y187106D01*
X90814Y187064D01*
X90689Y187009D01*
X90537Y186953D01*
X90329Y186884D01*
X90107Y186828D01*
X89857Y186787D01*
X89594Y186773D01*
X89483D01*
X89400Y186787D01*
X89289Y186801D01*
X89178Y186815D01*
X89039Y186842D01*
X88900Y186884D01*
X88581Y186981D01*
X88415Y187050D01*
X88249Y187134D01*
X88068Y187231D01*
X87902Y187355D01*
X87736Y187480D01*
X87583Y187633D01*
X87569Y187647D01*
X87541Y187675D01*
X87514Y187716D01*
X87458Y187785D01*
X87389Y187882D01*
X87319Y187980D01*
X87250Y188104D01*
X87181Y188243D01*
X87098Y188396D01*
X87028Y188562D01*
X86959Y188756D01*
X86890Y188950D01*
X86834Y189172D01*
X86806Y189408D01*
X86779Y189644D01*
X86765Y189907D01*
Y189921D01*
Y189977D01*
Y190046D01*
X86779Y190143D01*
X86792Y190268D01*
X86806Y190420D01*
X86834Y190573D01*
X86876Y190753D01*
X86973Y191114D01*
X87042Y191308D01*
X87125Y191516D01*
X87222Y191710D01*
X87347Y191890D01*
X87472Y192085D01*
X87625Y192251D01*
X87639Y192265D01*
X87666Y192293D01*
X87708Y192334D01*
X87777Y192390D01*
X87860Y192459D01*
X87971Y192542D01*
X88082Y192612D01*
X88221Y192709D01*
X88360Y192792D01*
X88526Y192861D01*
X88900Y193014D01*
X89095Y193069D01*
X89317Y193111D01*
X89538Y193139D01*
X89774Y193153D01*
X89871D01*
X89941Y193139D01*
D02*
G37*
G36*
X82452Y193097D02*
X82687Y193083D01*
X82937Y193069D01*
X83173Y193041D01*
X83381Y193014D01*
X83409D01*
X83506Y192986D01*
X83631Y192958D01*
X83797Y192917D01*
X83977Y192847D01*
X84171Y192764D01*
X84379Y192667D01*
X84560Y192556D01*
X84587Y192542D01*
X84643Y192501D01*
X84726Y192417D01*
X84837Y192320D01*
X84962Y192196D01*
X85087Y192029D01*
X85225Y191849D01*
X85336Y191641D01*
X85350Y191613D01*
X85378Y191544D01*
X85433Y191419D01*
X85489Y191252D01*
X85531Y191058D01*
X85586Y190836D01*
X85614Y190587D01*
X85627Y190323D01*
Y190309D01*
Y190268D01*
Y190212D01*
X85614Y190115D01*
X85600Y190018D01*
X85586Y189893D01*
X85558Y189755D01*
X85531Y189602D01*
X85433Y189283D01*
X85378Y189117D01*
X85295Y188937D01*
X85198Y188756D01*
X85100Y188590D01*
X84976Y188423D01*
X84837Y188257D01*
X84823Y188243D01*
X84795Y188215D01*
X84754Y188174D01*
X84684Y188132D01*
X84601Y188063D01*
X84490Y187993D01*
X84352Y187910D01*
X84199Y187841D01*
X84019Y187758D01*
X83811Y187675D01*
X83589Y187605D01*
X83325Y187550D01*
X83048Y187494D01*
X82743Y187453D01*
X82396Y187425D01*
X82036Y187411D01*
X79581D01*
Y183514D01*
X78305D01*
Y193111D01*
X82244D01*
X82452Y193097D01*
D02*
G37*
G36*
X195203Y24108D02*
X197506D01*
Y22929D01*
X195203D01*
Y18755D01*
X194122D01*
X187909Y23151D01*
Y24108D01*
X194122D01*
Y25412D01*
X195203D01*
Y24108D01*
D02*
G37*
G36*
X194538Y18062D02*
X194621Y18034D01*
X194732Y17992D01*
X194857Y17951D01*
X195009Y17895D01*
X195176Y17826D01*
X195356Y17743D01*
X195744Y17549D01*
X196133Y17299D01*
X196327Y17146D01*
X196521Y16994D01*
X196687Y16827D01*
X196854Y16633D01*
X196868Y16619D01*
X196895Y16592D01*
X196923Y16522D01*
X196979Y16453D01*
X197048Y16342D01*
X197117Y16231D01*
X197187Y16078D01*
X197256Y15926D01*
X197339Y15746D01*
X197409Y15552D01*
X197478Y15344D01*
X197547Y15122D01*
X197603Y14886D01*
X197630Y14636D01*
X197658Y14373D01*
X197672Y14095D01*
Y13943D01*
X197658Y13832D01*
Y13707D01*
X197644Y13554D01*
X197617Y13388D01*
X197589Y13194D01*
X197519Y12792D01*
X197409Y12376D01*
X197256Y11960D01*
X197159Y11765D01*
X197048Y11571D01*
X197034Y11557D01*
X197020Y11530D01*
X196979Y11474D01*
X196923Y11419D01*
X196868Y11336D01*
X196784Y11238D01*
X196687Y11128D01*
X196576Y11016D01*
X196452Y10906D01*
X196327Y10781D01*
X196008Y10531D01*
X195633Y10295D01*
X195217Y10087D01*
X195203D01*
X195162Y10060D01*
X195093Y10046D01*
X195009Y10004D01*
X194898Y9976D01*
X194760Y9935D01*
X194607Y9879D01*
X194441Y9838D01*
X194260Y9796D01*
X194052Y9741D01*
X193622Y9671D01*
X193137Y9616D01*
X192638Y9588D01*
X192624D01*
X192568D01*
X192485D01*
X192388Y9602D01*
X192250D01*
X192111Y9616D01*
X191931Y9630D01*
X191750Y9657D01*
X191348Y9727D01*
X190904Y9824D01*
X190460Y9962D01*
X190031Y10157D01*
X190017Y10171D01*
X189975Y10184D01*
X189920Y10212D01*
X189850Y10268D01*
X189753Y10323D01*
X189642Y10392D01*
X189393Y10573D01*
X189115Y10809D01*
X188838Y11086D01*
X188561Y11405D01*
X188325Y11779D01*
X188311Y11793D01*
X188297Y11835D01*
X188269Y11890D01*
X188228Y11960D01*
X188186Y12070D01*
X188144Y12182D01*
X188089Y12320D01*
X188034Y12473D01*
X187978Y12639D01*
X187923Y12819D01*
X187839Y13208D01*
X187770Y13651D01*
X187742Y14109D01*
Y14248D01*
X187756Y14345D01*
X187770Y14470D01*
X187784Y14622D01*
X187798Y14775D01*
X187839Y14955D01*
X187923Y15330D01*
X188047Y15746D01*
X188131Y15954D01*
X188228Y16148D01*
X188353Y16342D01*
X188477Y16536D01*
X188491Y16550D01*
X188505Y16578D01*
X188547Y16633D01*
X188616Y16703D01*
X188685Y16772D01*
X188782Y16869D01*
X188893Y16966D01*
X189004Y17077D01*
X189143Y17188D01*
X189309Y17299D01*
X189476Y17424D01*
X189656Y17535D01*
X189864Y17632D01*
X190072Y17743D01*
X190294Y17826D01*
X190544Y17909D01*
X190835Y16661D01*
X190821D01*
X190793Y16647D01*
X190738Y16619D01*
X190669Y16592D01*
X190585Y16564D01*
X190474Y16522D01*
X190252Y16411D01*
X190003Y16273D01*
X189753Y16106D01*
X189517Y15898D01*
X189309Y15676D01*
X189282Y15649D01*
X189226Y15565D01*
X189157Y15427D01*
X189060Y15246D01*
X188977Y15011D01*
X188893Y14747D01*
X188838Y14428D01*
X188824Y14081D01*
Y13971D01*
X188838Y13901D01*
Y13804D01*
X188852Y13693D01*
X188893Y13430D01*
X188949Y13138D01*
X189046Y12833D01*
X189185Y12514D01*
X189365Y12223D01*
Y12209D01*
X189393Y12195D01*
X189462Y12098D01*
X189573Y11973D01*
X189739Y11821D01*
X189947Y11641D01*
X190183Y11474D01*
X190474Y11322D01*
X190793Y11183D01*
X190807D01*
X190835Y11169D01*
X190877Y11155D01*
X190946Y11141D01*
X191029Y11114D01*
X191126Y11086D01*
X191362Y11044D01*
X191639Y10989D01*
X191944Y10933D01*
X192277Y10906D01*
X192638Y10892D01*
X192652D01*
X192693D01*
X192763D01*
X192846D01*
X192943Y10906D01*
X193068D01*
X193206Y10919D01*
X193359Y10933D01*
X193692Y10975D01*
X194052Y11044D01*
X194413Y11128D01*
X194774Y11238D01*
X194787D01*
X194815Y11252D01*
X194857Y11280D01*
X194926Y11308D01*
X195093Y11391D01*
X195287Y11516D01*
X195509Y11668D01*
X195744Y11862D01*
X195952Y12084D01*
X196147Y12348D01*
Y12362D01*
X196160Y12390D01*
X196188Y12431D01*
X196216Y12487D01*
X196244Y12556D01*
X196285Y12639D01*
X196368Y12833D01*
X196452Y13083D01*
X196521Y13360D01*
X196576Y13665D01*
X196590Y13984D01*
Y14081D01*
X196576Y14165D01*
Y14262D01*
X196563Y14359D01*
X196507Y14608D01*
X196438Y14900D01*
X196327Y15191D01*
X196174Y15496D01*
X196091Y15649D01*
X195980Y15787D01*
X195966Y15801D01*
X195952Y15815D01*
X195911Y15857D01*
X195869Y15912D01*
X195800Y15968D01*
X195717Y16037D01*
X195633Y16120D01*
X195522Y16189D01*
X195398Y16273D01*
X195259Y16370D01*
X195120Y16453D01*
X194954Y16536D01*
X194774Y16605D01*
X194579Y16675D01*
X194371Y16744D01*
X194149Y16800D01*
X194468Y18075D01*
X194482D01*
X194538Y18062D01*
D02*
G37*
G36*
X69682Y222307D02*
X69807Y222293D01*
X69959Y222279D01*
X70112Y222265D01*
X70292Y222223D01*
X70667Y222140D01*
X71083Y222015D01*
X71291Y221932D01*
X71485Y221835D01*
X71679Y221710D01*
X71873Y221586D01*
X71887Y221572D01*
X71915Y221558D01*
X71970Y221516D01*
X72039Y221447D01*
X72109Y221377D01*
X72206Y221280D01*
X72303Y221169D01*
X72414Y221059D01*
X72525Y220920D01*
X72636Y220753D01*
X72761Y220587D01*
X72872Y220407D01*
X72969Y220199D01*
X73080Y219991D01*
X73163Y219769D01*
X73246Y219519D01*
X71998Y219228D01*
Y219242D01*
X71984Y219269D01*
X71956Y219325D01*
X71929Y219394D01*
X71901Y219478D01*
X71859Y219588D01*
X71748Y219810D01*
X71610Y220060D01*
X71443Y220310D01*
X71235Y220545D01*
X71013Y220753D01*
X70985Y220781D01*
X70902Y220837D01*
X70764Y220906D01*
X70583Y221003D01*
X70348Y221086D01*
X70084Y221169D01*
X69765Y221225D01*
X69418Y221239D01*
X69307D01*
X69238Y221225D01*
X69141D01*
X69030Y221211D01*
X68767Y221169D01*
X68475Y221114D01*
X68170Y221017D01*
X67851Y220878D01*
X67560Y220698D01*
X67546D01*
X67532Y220670D01*
X67435Y220601D01*
X67310Y220490D01*
X67158Y220323D01*
X66978Y220115D01*
X66811Y219880D01*
X66659Y219588D01*
X66520Y219269D01*
Y219256D01*
X66506Y219228D01*
X66492Y219186D01*
X66478Y219117D01*
X66451Y219034D01*
X66423Y218937D01*
X66381Y218701D01*
X66326Y218424D01*
X66270Y218118D01*
X66242Y217785D01*
X66229Y217425D01*
Y217411D01*
Y217369D01*
Y217300D01*
Y217217D01*
X66242Y217120D01*
Y216995D01*
X66256Y216856D01*
X66270Y216704D01*
X66312Y216371D01*
X66381Y216010D01*
X66464Y215650D01*
X66575Y215289D01*
Y215275D01*
X66589Y215248D01*
X66617Y215206D01*
X66645Y215137D01*
X66728Y214970D01*
X66853Y214776D01*
X67005Y214554D01*
X67200Y214318D01*
X67421Y214110D01*
X67685Y213916D01*
X67699D01*
X67726Y213902D01*
X67768Y213875D01*
X67824Y213847D01*
X67893Y213819D01*
X67976Y213778D01*
X68170Y213694D01*
X68420Y213611D01*
X68697Y213542D01*
X69002Y213486D01*
X69321Y213472D01*
X69418D01*
X69502Y213486D01*
X69599D01*
X69696Y213500D01*
X69945Y213556D01*
X70237Y213625D01*
X70528Y213736D01*
X70833Y213888D01*
X70985Y213972D01*
X71124Y214083D01*
X71138Y214097D01*
X71152Y214110D01*
X71194Y214152D01*
X71249Y214194D01*
X71304Y214263D01*
X71374Y214346D01*
X71457Y214429D01*
X71526Y214540D01*
X71610Y214665D01*
X71707Y214804D01*
X71790Y214942D01*
X71873Y215109D01*
X71943Y215289D01*
X72012Y215483D01*
X72081Y215691D01*
X72137Y215913D01*
X73412Y215594D01*
Y215580D01*
X73399Y215525D01*
X73371Y215442D01*
X73329Y215331D01*
X73288Y215206D01*
X73232Y215053D01*
X73163Y214887D01*
X73080Y214707D01*
X72885Y214318D01*
X72636Y213930D01*
X72483Y213736D01*
X72331Y213542D01*
X72164Y213375D01*
X71970Y213209D01*
X71956Y213195D01*
X71929Y213167D01*
X71859Y213140D01*
X71790Y213084D01*
X71679Y213015D01*
X71568Y212945D01*
X71416Y212876D01*
X71263Y212807D01*
X71083Y212724D01*
X70889Y212654D01*
X70680Y212585D01*
X70458Y212516D01*
X70223Y212460D01*
X69973Y212432D01*
X69710Y212405D01*
X69432Y212391D01*
X69280D01*
X69169Y212405D01*
X69044D01*
X68891Y212418D01*
X68725Y212446D01*
X68531Y212474D01*
X68129Y212543D01*
X67713Y212654D01*
X67297Y212807D01*
X67102Y212904D01*
X66908Y213015D01*
X66894Y213029D01*
X66867Y213043D01*
X66811Y213084D01*
X66756Y213140D01*
X66673Y213195D01*
X66575Y213278D01*
X66464Y213375D01*
X66354Y213486D01*
X66242Y213611D01*
X66118Y213736D01*
X65868Y214055D01*
X65632Y214429D01*
X65424Y214845D01*
Y214859D01*
X65397Y214901D01*
X65383Y214970D01*
X65341Y215053D01*
X65313Y215164D01*
X65272Y215303D01*
X65216Y215456D01*
X65175Y215622D01*
X65133Y215802D01*
X65078Y216010D01*
X65008Y216440D01*
X64953Y216926D01*
X64925Y217425D01*
Y217439D01*
Y217494D01*
Y217577D01*
X64939Y217675D01*
Y217813D01*
X64953Y217952D01*
X64967Y218132D01*
X64994Y218312D01*
X65064Y218715D01*
X65161Y219158D01*
X65300Y219602D01*
X65494Y220032D01*
X65507Y220046D01*
X65521Y220088D01*
X65549Y220143D01*
X65605Y220212D01*
X65660Y220310D01*
X65729Y220420D01*
X65910Y220670D01*
X66146Y220947D01*
X66423Y221225D01*
X66742Y221502D01*
X67116Y221738D01*
X67130Y221752D01*
X67172Y221766D01*
X67227Y221793D01*
X67297Y221835D01*
X67407Y221877D01*
X67518Y221918D01*
X67657Y221974D01*
X67810Y222029D01*
X67976Y222085D01*
X68156Y222140D01*
X68545Y222223D01*
X68988Y222293D01*
X69446Y222320D01*
X69585D01*
X69682Y222307D01*
D02*
G37*
G36*
X77795Y222182D02*
X77975Y222154D01*
X78197Y222113D01*
X78447Y222043D01*
X78696Y221960D01*
X78946Y221849D01*
X78960D01*
X78974Y221835D01*
X79057Y221793D01*
X79182Y221710D01*
X79320Y221613D01*
X79487Y221474D01*
X79653Y221322D01*
X79820Y221142D01*
X79958Y220934D01*
X79972Y220906D01*
X80014Y220837D01*
X80069Y220712D01*
X80139Y220559D01*
X80208Y220379D01*
X80264Y220171D01*
X80305Y219935D01*
X80319Y219699D01*
Y219672D01*
Y219588D01*
X80305Y219478D01*
X80277Y219325D01*
X80236Y219145D01*
X80166Y218951D01*
X80083Y218756D01*
X79972Y218562D01*
X79958Y218534D01*
X79917Y218479D01*
X79834Y218382D01*
X79723Y218271D01*
X79584Y218146D01*
X79418Y218007D01*
X79223Y217883D01*
X78988Y217758D01*
X79001D01*
X79029Y217744D01*
X79071Y217730D01*
X79126Y217716D01*
X79279Y217661D01*
X79473Y217577D01*
X79695Y217467D01*
X79917Y217328D01*
X80125Y217148D01*
X80319Y216940D01*
X80333Y216912D01*
X80388Y216829D01*
X80471Y216690D01*
X80555Y216510D01*
X80638Y216288D01*
X80721Y216024D01*
X80777Y215719D01*
X80791Y215386D01*
Y215372D01*
Y215331D01*
Y215261D01*
X80777Y215178D01*
X80763Y215067D01*
X80735Y214942D01*
X80707Y214804D01*
X80680Y214651D01*
X80569Y214318D01*
X80485Y214138D01*
X80402Y213972D01*
X80291Y213791D01*
X80166Y213611D01*
X80028Y213431D01*
X79861Y213264D01*
X79847Y213251D01*
X79820Y213223D01*
X79764Y213181D01*
X79695Y213126D01*
X79612Y213056D01*
X79501Y212987D01*
X79376Y212904D01*
X79223Y212834D01*
X79071Y212751D01*
X78891Y212668D01*
X78710Y212599D01*
X78502Y212529D01*
X78280Y212474D01*
X78045Y212432D01*
X77809Y212405D01*
X77545Y212391D01*
X77421D01*
X77337Y212405D01*
X77226Y212418D01*
X77101Y212432D01*
X76963Y212460D01*
X76810Y212488D01*
X76477Y212571D01*
X76131Y212710D01*
X75950Y212793D01*
X75784Y212890D01*
X75618Y213015D01*
X75451Y213140D01*
X75437Y213153D01*
X75410Y213181D01*
X75368Y213223D01*
X75326Y213278D01*
X75257Y213348D01*
X75188Y213445D01*
X75104Y213542D01*
X75021Y213667D01*
X74938Y213805D01*
X74855Y213944D01*
X74702Y214277D01*
X74577Y214665D01*
X74536Y214873D01*
X74508Y215095D01*
X75687Y215248D01*
Y215234D01*
X75701Y215206D01*
X75715Y215151D01*
X75729Y215081D01*
X75742Y214998D01*
X75770Y214901D01*
X75840Y214693D01*
X75937Y214443D01*
X76061Y214207D01*
X76200Y213986D01*
X76367Y213791D01*
X76394Y213778D01*
X76450Y213722D01*
X76561Y213653D01*
X76699Y213583D01*
X76866Y213500D01*
X77074Y213431D01*
X77309Y213375D01*
X77559Y213361D01*
X77642D01*
X77698Y213375D01*
X77850Y213389D01*
X78045Y213431D01*
X78266Y213500D01*
X78502Y213597D01*
X78738Y213736D01*
X78960Y213930D01*
X78988Y213958D01*
X79057Y214041D01*
X79140Y214166D01*
X79251Y214332D01*
X79362Y214540D01*
X79445Y214776D01*
X79515Y215053D01*
X79542Y215359D01*
Y215372D01*
Y215400D01*
Y215442D01*
X79528Y215497D01*
X79515Y215650D01*
X79473Y215830D01*
X79418Y216052D01*
X79320Y216274D01*
X79182Y216496D01*
X79001Y216704D01*
X78974Y216731D01*
X78904Y216787D01*
X78793Y216870D01*
X78641Y216967D01*
X78447Y217064D01*
X78211Y217148D01*
X77948Y217203D01*
X77656Y217231D01*
X77531D01*
X77434Y217217D01*
X77309Y217203D01*
X77171Y217175D01*
X77004Y217148D01*
X76824Y217106D01*
X76963Y218146D01*
X77032D01*
X77088Y218132D01*
X77268D01*
X77421Y218160D01*
X77601Y218188D01*
X77809Y218229D01*
X78045Y218299D01*
X78266Y218396D01*
X78502Y218521D01*
X78516D01*
X78530Y218534D01*
X78599Y218590D01*
X78696Y218687D01*
X78807Y218812D01*
X78918Y218992D01*
X79015Y219200D01*
X79085Y219436D01*
X79112Y219575D01*
Y219727D01*
Y219741D01*
Y219755D01*
Y219838D01*
X79085Y219949D01*
X79057Y220102D01*
X79001Y220268D01*
X78932Y220448D01*
X78821Y220629D01*
X78669Y220795D01*
X78655Y220809D01*
X78585Y220864D01*
X78488Y220934D01*
X78363Y221017D01*
X78197Y221086D01*
X78003Y221155D01*
X77781Y221211D01*
X77531Y221225D01*
X77421D01*
X77296Y221197D01*
X77129Y221169D01*
X76949Y221114D01*
X76769Y221045D01*
X76575Y220934D01*
X76394Y220795D01*
X76380Y220781D01*
X76325Y220712D01*
X76242Y220615D01*
X76145Y220476D01*
X76048Y220296D01*
X75950Y220074D01*
X75867Y219810D01*
X75812Y219505D01*
X74633Y219713D01*
Y219727D01*
X74647Y219769D01*
X74661Y219824D01*
X74675Y219907D01*
X74702Y220005D01*
X74744Y220115D01*
X74827Y220379D01*
X74966Y220684D01*
X75132Y220989D01*
X75340Y221280D01*
X75604Y221544D01*
X75618Y221558D01*
X75645Y221572D01*
X75687Y221599D01*
X75742Y221641D01*
X75812Y221696D01*
X75909Y221752D01*
X76006Y221807D01*
X76131Y221877D01*
X76408Y221988D01*
X76727Y222099D01*
X77101Y222168D01*
X77296Y222196D01*
X77642D01*
X77795Y222182D01*
D02*
G37*
G36*
X69418Y241621D02*
X69543Y241607D01*
X69696Y241593D01*
X69848Y241579D01*
X70028Y241537D01*
X70403Y241454D01*
X70819Y241329D01*
X71027Y241246D01*
X71221Y241149D01*
X71415Y241024D01*
X71609Y240900D01*
X71623Y240886D01*
X71651Y240872D01*
X71706Y240830D01*
X71776Y240761D01*
X71845Y240692D01*
X71942Y240594D01*
X72039Y240483D01*
X72150Y240373D01*
X72261Y240234D01*
X72372Y240067D01*
X72497Y239901D01*
X72608Y239721D01*
X72705Y239513D01*
X72816Y239305D01*
X72899Y239083D01*
X72982Y238833D01*
X71734Y238542D01*
Y238556D01*
X71720Y238584D01*
X71693Y238639D01*
X71665Y238708D01*
X71637Y238792D01*
X71596Y238902D01*
X71484Y239124D01*
X71346Y239374D01*
X71179Y239624D01*
X70971Y239859D01*
X70750Y240067D01*
X70722Y240095D01*
X70638Y240151D01*
X70500Y240220D01*
X70320Y240317D01*
X70084Y240400D01*
X69820Y240483D01*
X69501Y240539D01*
X69155Y240553D01*
X69044D01*
X68974Y240539D01*
X68877D01*
X68766Y240525D01*
X68503Y240483D01*
X68212Y240428D01*
X67906Y240331D01*
X67587Y240192D01*
X67296Y240012D01*
X67282D01*
X67269Y239984D01*
X67171Y239915D01*
X67047Y239804D01*
X66894Y239638D01*
X66714Y239429D01*
X66547Y239194D01*
X66395Y238902D01*
X66256Y238584D01*
Y238570D01*
X66242Y238542D01*
X66228Y238500D01*
X66214Y238431D01*
X66187Y238348D01*
X66159Y238251D01*
X66117Y238015D01*
X66062Y237738D01*
X66006Y237432D01*
X65979Y237100D01*
X65965Y236739D01*
Y236725D01*
Y236684D01*
Y236614D01*
Y236531D01*
X65979Y236434D01*
Y236309D01*
X65993Y236170D01*
X66006Y236018D01*
X66048Y235685D01*
X66117Y235324D01*
X66201Y234964D01*
X66312Y234603D01*
Y234589D01*
X66325Y234562D01*
X66353Y234520D01*
X66381Y234451D01*
X66464Y234284D01*
X66589Y234090D01*
X66741Y233868D01*
X66936Y233633D01*
X67158Y233424D01*
X67421Y233230D01*
X67435D01*
X67463Y233216D01*
X67504Y233189D01*
X67560Y233161D01*
X67629Y233133D01*
X67712Y233092D01*
X67906Y233008D01*
X68156Y232925D01*
X68433Y232856D01*
X68739Y232800D01*
X69057Y232787D01*
X69155D01*
X69238Y232800D01*
X69335D01*
X69432Y232814D01*
X69682Y232870D01*
X69973Y232939D01*
X70264Y233050D01*
X70569Y233203D01*
X70722Y233286D01*
X70860Y233397D01*
X70874Y233411D01*
X70888Y233424D01*
X70930Y233466D01*
X70985Y233508D01*
X71041Y233577D01*
X71110Y233660D01*
X71193Y233743D01*
X71263Y233854D01*
X71346Y233979D01*
X71443Y234118D01*
X71526Y234257D01*
X71609Y234423D01*
X71679Y234603D01*
X71748Y234797D01*
X71817Y235005D01*
X71873Y235227D01*
X73149Y234908D01*
Y234895D01*
X73135Y234839D01*
X73107Y234756D01*
X73066Y234645D01*
X73024Y234520D01*
X72968Y234368D01*
X72899Y234201D01*
X72816Y234021D01*
X72622Y233633D01*
X72372Y233244D01*
X72220Y233050D01*
X72067Y232856D01*
X71901Y232689D01*
X71706Y232523D01*
X71693Y232509D01*
X71665Y232481D01*
X71596Y232454D01*
X71526Y232398D01*
X71415Y232329D01*
X71304Y232260D01*
X71152Y232190D01*
X70999Y232121D01*
X70819Y232038D01*
X70625Y231968D01*
X70417Y231899D01*
X70195Y231830D01*
X69959Y231774D01*
X69709Y231746D01*
X69446Y231719D01*
X69169Y231705D01*
X69016D01*
X68905Y231719D01*
X68780D01*
X68628Y231733D01*
X68461Y231760D01*
X68267Y231788D01*
X67865Y231857D01*
X67449Y231968D01*
X67033Y232121D01*
X66839Y232218D01*
X66644Y232329D01*
X66631Y232343D01*
X66603Y232357D01*
X66547Y232398D01*
X66492Y232454D01*
X66409Y232509D01*
X66312Y232592D01*
X66201Y232689D01*
X66090Y232800D01*
X65979Y232925D01*
X65854Y233050D01*
X65604Y233369D01*
X65369Y233743D01*
X65160Y234160D01*
Y234173D01*
X65133Y234215D01*
X65119Y234284D01*
X65077Y234368D01*
X65050Y234478D01*
X65008Y234617D01*
X64953Y234770D01*
X64911Y234936D01*
X64869Y235116D01*
X64814Y235324D01*
X64745Y235754D01*
X64689Y236240D01*
X64661Y236739D01*
Y236753D01*
Y236808D01*
Y236892D01*
X64675Y236989D01*
Y237127D01*
X64689Y237266D01*
X64703Y237446D01*
X64731Y237627D01*
X64800Y238029D01*
X64897Y238473D01*
X65036Y238916D01*
X65230Y239346D01*
X65244Y239360D01*
X65258Y239402D01*
X65285Y239457D01*
X65341Y239527D01*
X65396Y239624D01*
X65466Y239735D01*
X65646Y239984D01*
X65882Y240262D01*
X66159Y240539D01*
X66478Y240816D01*
X66852Y241052D01*
X66866Y241066D01*
X66908Y241080D01*
X66963Y241108D01*
X67033Y241149D01*
X67144Y241191D01*
X67255Y241232D01*
X67393Y241288D01*
X67546Y241343D01*
X67712Y241399D01*
X67893Y241454D01*
X68281Y241537D01*
X68725Y241607D01*
X69182Y241635D01*
X69321D01*
X69418Y241621D01*
D02*
G37*
G36*
X77642Y241496D02*
X77753Y241482D01*
X77892Y241468D01*
X78044Y241440D01*
X78197Y241413D01*
X78557Y241316D01*
X78918Y241177D01*
X79098Y241094D01*
X79279Y240997D01*
X79445Y240872D01*
X79598Y240733D01*
X79611Y240719D01*
X79639Y240705D01*
X79667Y240650D01*
X79722Y240594D01*
X79792Y240525D01*
X79861Y240428D01*
X79930Y240331D01*
X80014Y240206D01*
X80152Y239943D01*
X80291Y239610D01*
X80346Y239443D01*
X80374Y239249D01*
X80402Y239055D01*
X80416Y238847D01*
Y238819D01*
Y238750D01*
X80402Y238639D01*
X80388Y238486D01*
X80360Y238320D01*
X80305Y238126D01*
X80249Y237918D01*
X80166Y237710D01*
X80152Y237682D01*
X80125Y237613D01*
X80069Y237502D01*
X79986Y237349D01*
X79875Y237183D01*
X79736Y236975D01*
X79570Y236767D01*
X79376Y236531D01*
X79348Y236503D01*
X79279Y236420D01*
X79209Y236351D01*
X79140Y236281D01*
X79057Y236198D01*
X78946Y236087D01*
X78835Y235976D01*
X78696Y235851D01*
X78557Y235713D01*
X78391Y235560D01*
X78211Y235408D01*
X78017Y235227D01*
X77795Y235047D01*
X77573Y234853D01*
X77559Y234839D01*
X77531Y234811D01*
X77476Y234770D01*
X77406Y234714D01*
X77323Y234631D01*
X77226Y234548D01*
X77004Y234368D01*
X76768Y234160D01*
X76547Y233951D01*
X76352Y233771D01*
X76269Y233702D01*
X76200Y233633D01*
X76186Y233619D01*
X76144Y233577D01*
X76089Y233522D01*
X76020Y233438D01*
X75950Y233341D01*
X75867Y233244D01*
X75700Y233008D01*
X80430D01*
Y231871D01*
X74064D01*
Y231885D01*
Y231941D01*
Y232024D01*
X74078Y232135D01*
X74092Y232260D01*
X74120Y232398D01*
X74147Y232537D01*
X74203Y232689D01*
Y232703D01*
X74217Y232717D01*
X74244Y232800D01*
X74300Y232925D01*
X74383Y233092D01*
X74494Y233286D01*
X74633Y233508D01*
X74785Y233730D01*
X74979Y233965D01*
Y233979D01*
X75007Y233993D01*
X75076Y234076D01*
X75201Y234201D01*
X75381Y234381D01*
X75590Y234589D01*
X75853Y234839D01*
X76172Y235116D01*
X76519Y235408D01*
X76533Y235422D01*
X76588Y235463D01*
X76671Y235532D01*
X76768Y235616D01*
X76893Y235727D01*
X77046Y235851D01*
X77198Y235990D01*
X77379Y236143D01*
X77725Y236476D01*
X78072Y236808D01*
X78238Y236975D01*
X78391Y237141D01*
X78530Y237294D01*
X78641Y237446D01*
Y237460D01*
X78668Y237474D01*
X78696Y237516D01*
X78724Y237571D01*
X78821Y237724D01*
X78932Y237904D01*
X79029Y238126D01*
X79126Y238362D01*
X79181Y238625D01*
X79209Y238875D01*
Y238889D01*
Y238902D01*
X79195Y238986D01*
X79181Y239124D01*
X79140Y239277D01*
X79084Y239471D01*
X78987Y239665D01*
X78863Y239859D01*
X78696Y240054D01*
X78668Y240081D01*
X78599Y240137D01*
X78502Y240206D01*
X78349Y240303D01*
X78155Y240386D01*
X77933Y240470D01*
X77670Y240525D01*
X77379Y240539D01*
X77295D01*
X77240Y240525D01*
X77073Y240511D01*
X76879Y240470D01*
X76671Y240414D01*
X76435Y240317D01*
X76214Y240192D01*
X76006Y240026D01*
X75978Y239998D01*
X75922Y239929D01*
X75839Y239818D01*
X75756Y239651D01*
X75659Y239457D01*
X75576Y239208D01*
X75520Y238930D01*
X75493Y238611D01*
X74286Y238736D01*
Y238750D01*
X74300Y238792D01*
Y238861D01*
X74314Y238958D01*
X74341Y239069D01*
X74369Y239194D01*
X74411Y239346D01*
X74452Y239499D01*
X74563Y239832D01*
X74730Y240165D01*
X74827Y240331D01*
X74952Y240497D01*
X75076Y240650D01*
X75215Y240789D01*
X75229Y240802D01*
X75257Y240816D01*
X75298Y240858D01*
X75368Y240900D01*
X75451Y240955D01*
X75548Y241010D01*
X75659Y241080D01*
X75798Y241149D01*
X75950Y241218D01*
X76117Y241288D01*
X76297Y241343D01*
X76491Y241399D01*
X76699Y241440D01*
X76921Y241482D01*
X77157Y241496D01*
X77406Y241510D01*
X77545D01*
X77642Y241496D01*
D02*
G37*
G36*
X174798Y26868D02*
X167296D01*
X167309Y26854D01*
X167365Y26785D01*
X167448Y26702D01*
X167545Y26563D01*
X167670Y26410D01*
X167809Y26216D01*
X167961Y25994D01*
X168114Y25745D01*
Y25731D01*
X168128Y25717D01*
X168183Y25634D01*
X168253Y25495D01*
X168336Y25329D01*
X168433Y25134D01*
X168530Y24926D01*
X168627Y24718D01*
X168710Y24510D01*
X167573D01*
Y24524D01*
X167545Y24552D01*
X167531Y24607D01*
X167490Y24677D01*
X167448Y24760D01*
X167393Y24857D01*
X167254Y25093D01*
X167101Y25370D01*
X166907Y25647D01*
X166685Y25939D01*
X166450Y26230D01*
X166436Y26244D01*
X166422Y26258D01*
X166380Y26299D01*
X166339Y26355D01*
X166200Y26480D01*
X166034Y26646D01*
X165839Y26812D01*
X165618Y26993D01*
X165396Y27145D01*
X165160Y27284D01*
Y28047D01*
X174798D01*
Y26868D01*
D02*
G37*
G36*
X171831Y22513D02*
X171914Y22485D01*
X172025Y22444D01*
X172150Y22402D01*
X172302Y22347D01*
X172468Y22278D01*
X172649Y22194D01*
X173037Y22000D01*
X173425Y21751D01*
X173620Y21598D01*
X173814Y21445D01*
X173980Y21279D01*
X174147Y21085D01*
X174160Y21071D01*
X174188Y21043D01*
X174216Y20974D01*
X174271Y20905D01*
X174341Y20793D01*
X174410Y20683D01*
X174479Y20530D01*
X174549Y20378D01*
X174632Y20197D01*
X174701Y20003D01*
X174771Y19795D01*
X174840Y19573D01*
X174895Y19337D01*
X174923Y19088D01*
X174951Y18824D01*
X174965Y18547D01*
Y18394D01*
X174951Y18283D01*
Y18159D01*
X174937Y18006D01*
X174909Y17840D01*
X174882Y17645D01*
X174812Y17243D01*
X174701Y16827D01*
X174549Y16411D01*
X174452Y16217D01*
X174341Y16023D01*
X174327Y16009D01*
X174313Y15981D01*
X174271Y15926D01*
X174216Y15870D01*
X174160Y15787D01*
X174077Y15690D01*
X173980Y15579D01*
X173869Y15468D01*
X173744Y15357D01*
X173620Y15232D01*
X173301Y14983D01*
X172926Y14747D01*
X172510Y14539D01*
X172496D01*
X172455Y14511D01*
X172385Y14497D01*
X172302Y14456D01*
X172191Y14428D01*
X172052Y14386D01*
X171900Y14331D01*
X171733Y14289D01*
X171553Y14248D01*
X171345Y14192D01*
X170915Y14123D01*
X170430Y14067D01*
X169931Y14040D01*
X169917D01*
X169861D01*
X169778D01*
X169681Y14053D01*
X169542D01*
X169404Y14067D01*
X169223Y14081D01*
X169043Y14109D01*
X168641Y14178D01*
X168197Y14275D01*
X167753Y14414D01*
X167323Y14608D01*
X167309Y14622D01*
X167268Y14636D01*
X167212Y14664D01*
X167143Y14719D01*
X167046Y14775D01*
X166935Y14844D01*
X166685Y15024D01*
X166408Y15260D01*
X166131Y15537D01*
X165853Y15856D01*
X165618Y16231D01*
X165604Y16245D01*
X165590Y16286D01*
X165562Y16342D01*
X165520Y16411D01*
X165479Y16522D01*
X165437Y16633D01*
X165382Y16772D01*
X165326Y16924D01*
X165271Y17091D01*
X165215Y17271D01*
X165132Y17659D01*
X165063Y18103D01*
X165035Y18561D01*
Y18699D01*
X165049Y18796D01*
X165063Y18921D01*
X165077Y19074D01*
X165091Y19226D01*
X165132Y19407D01*
X165215Y19781D01*
X165340Y20197D01*
X165423Y20405D01*
X165520Y20599D01*
X165645Y20793D01*
X165770Y20988D01*
X165784Y21002D01*
X165798Y21029D01*
X165839Y21085D01*
X165909Y21154D01*
X165978Y21223D01*
X166075Y21321D01*
X166186Y21418D01*
X166297Y21529D01*
X166436Y21639D01*
X166602Y21751D01*
X166769Y21875D01*
X166949Y21986D01*
X167157Y22083D01*
X167365Y22194D01*
X167587Y22278D01*
X167836Y22361D01*
X168128Y21112D01*
X168114D01*
X168086Y21099D01*
X168031Y21071D01*
X167961Y21043D01*
X167878Y21015D01*
X167767Y20974D01*
X167545Y20863D01*
X167296Y20724D01*
X167046Y20558D01*
X166810Y20350D01*
X166602Y20128D01*
X166574Y20100D01*
X166519Y20017D01*
X166450Y19878D01*
X166353Y19698D01*
X166269Y19462D01*
X166186Y19199D01*
X166131Y18880D01*
X166117Y18533D01*
Y18422D01*
X166131Y18353D01*
Y18256D01*
X166145Y18145D01*
X166186Y17881D01*
X166242Y17590D01*
X166339Y17285D01*
X166477Y16966D01*
X166658Y16675D01*
Y16661D01*
X166685Y16647D01*
X166755Y16550D01*
X166866Y16425D01*
X167032Y16272D01*
X167240Y16092D01*
X167476Y15926D01*
X167767Y15773D01*
X168086Y15634D01*
X168100D01*
X168128Y15621D01*
X168169Y15607D01*
X168239Y15593D01*
X168322Y15565D01*
X168419Y15537D01*
X168655Y15496D01*
X168932Y15440D01*
X169237Y15385D01*
X169570Y15357D01*
X169931Y15343D01*
X169944D01*
X169986D01*
X170055D01*
X170139D01*
X170236Y15357D01*
X170361D01*
X170499Y15371D01*
X170652Y15385D01*
X170985Y15426D01*
X171345Y15496D01*
X171706Y15579D01*
X172066Y15690D01*
X172080D01*
X172108Y15704D01*
X172150Y15732D01*
X172219Y15759D01*
X172385Y15842D01*
X172579Y15967D01*
X172801Y16120D01*
X173037Y16314D01*
X173245Y16536D01*
X173439Y16799D01*
Y16813D01*
X173453Y16841D01*
X173481Y16883D01*
X173509Y16938D01*
X173536Y17007D01*
X173578Y17091D01*
X173661Y17285D01*
X173744Y17535D01*
X173814Y17812D01*
X173869Y18117D01*
X173883Y18436D01*
Y18533D01*
X173869Y18616D01*
Y18713D01*
X173855Y18810D01*
X173800Y19060D01*
X173731Y19351D01*
X173620Y19642D01*
X173467Y19948D01*
X173384Y20100D01*
X173273Y20239D01*
X173259Y20253D01*
X173245Y20266D01*
X173204Y20308D01*
X173162Y20364D01*
X173093Y20419D01*
X173009Y20488D01*
X172926Y20572D01*
X172815Y20641D01*
X172690Y20724D01*
X172552Y20821D01*
X172413Y20905D01*
X172247Y20988D01*
X172066Y21057D01*
X171872Y21126D01*
X171664Y21196D01*
X171442Y21251D01*
X171761Y22527D01*
X171775D01*
X171831Y22513D01*
D02*
G37*
%LPC*%
G36*
X407327Y171225D02*
X407258D01*
X407202Y171211D01*
X407049Y171198D01*
X406869Y171142D01*
X406661Y171073D01*
X406439Y170948D01*
X406217Y170795D01*
X406106Y170684D01*
X406009Y170574D01*
Y170560D01*
X405982Y170546D01*
X405968Y170504D01*
X405926Y170449D01*
X405885Y170379D01*
X405843Y170296D01*
X405801Y170199D01*
X405746Y170088D01*
X405690Y169949D01*
X405649Y169797D01*
X405607Y169630D01*
X405566Y169450D01*
X405538Y169256D01*
X405510Y169034D01*
X405482Y168798D01*
Y168549D01*
Y168535D01*
Y168493D01*
Y168424D01*
X405496Y168327D01*
Y168216D01*
X405510Y168091D01*
X405552Y167800D01*
X405621Y167481D01*
X405718Y167148D01*
X405857Y166829D01*
X405940Y166690D01*
X406037Y166552D01*
X406051D01*
X406065Y166524D01*
X406134Y166455D01*
X406259Y166344D01*
X406412Y166233D01*
X406606Y166108D01*
X406842Y165997D01*
X407091Y165928D01*
X407230Y165914D01*
X407369Y165900D01*
X407438D01*
X407493Y165914D01*
X407646Y165928D01*
X407826Y165983D01*
X408034Y166052D01*
X408256Y166163D01*
X408478Y166316D01*
X408589Y166413D01*
X408686Y166524D01*
Y166538D01*
X408714Y166552D01*
X408741Y166593D01*
X408769Y166649D01*
X408811Y166718D01*
X408866Y166787D01*
X408908Y166898D01*
X408963Y167009D01*
X409019Y167134D01*
X409060Y167273D01*
X409116Y167439D01*
X409157Y167606D01*
X409185Y167800D01*
X409213Y167994D01*
X409241Y168216D01*
Y168452D01*
Y168465D01*
Y168521D01*
Y168590D01*
X409227Y168687D01*
Y168798D01*
X409213Y168937D01*
X409199Y169090D01*
X409171Y169256D01*
X409102Y169589D01*
X409005Y169936D01*
X408866Y170268D01*
X408783Y170407D01*
X408686Y170546D01*
Y170560D01*
X408658Y170574D01*
X408589Y170657D01*
X408464Y170768D01*
X408312Y170893D01*
X408117Y171017D01*
X407882Y171114D01*
X407618Y171198D01*
X407479Y171211D01*
X407327Y171225D01*
D02*
G37*
G36*
X397245Y168576D02*
X397231D01*
X397217Y168563D01*
X397175Y168549D01*
X397120Y168535D01*
X397050Y168507D01*
X396967Y168479D01*
X396870Y168452D01*
X396759Y168424D01*
X396634Y168382D01*
X396482Y168355D01*
X396329Y168313D01*
X396149Y168271D01*
X395955Y168230D01*
X395761Y168188D01*
X395539Y168160D01*
X395303Y168119D01*
X395275D01*
X395192Y168105D01*
X395053Y168077D01*
X394901Y168049D01*
X394734Y168022D01*
X394568Y167980D01*
X394415Y167938D01*
X394277Y167883D01*
X394263D01*
X394221Y167855D01*
X394166Y167828D01*
X394110Y167786D01*
X393944Y167675D01*
X393805Y167509D01*
Y167495D01*
X393778Y167467D01*
X393764Y167411D01*
X393736Y167342D01*
X393708Y167259D01*
X393680Y167176D01*
X393666Y167065D01*
X393653Y166954D01*
Y166940D01*
Y166871D01*
X393666Y166787D01*
X393694Y166677D01*
X393736Y166552D01*
X393805Y166427D01*
X393888Y166288D01*
X393999Y166163D01*
X394013Y166150D01*
X394069Y166122D01*
X394152Y166066D01*
X394263Y166011D01*
X394415Y165955D01*
X394596Y165900D01*
X394804Y165872D01*
X395053Y165858D01*
X395164D01*
X395303Y165872D01*
X395456Y165900D01*
X395650Y165928D01*
X395844Y165983D01*
X396052Y166052D01*
X396260Y166150D01*
X396288Y166163D01*
X396343Y166205D01*
X396440Y166274D01*
X396551Y166371D01*
X396676Y166482D01*
X396815Y166621D01*
X396926Y166787D01*
X397037Y166968D01*
X397050Y166982D01*
X397064Y167037D01*
X397092Y167134D01*
X397134Y167259D01*
X397175Y167425D01*
X397203Y167619D01*
X397217Y167855D01*
X397231Y168133D01*
X397245Y168576D01*
D02*
G37*
G36*
X338332Y168576D02*
X338318D01*
X338304Y168563D01*
X338262Y168549D01*
X338207Y168535D01*
X338137Y168507D01*
X338054Y168479D01*
X337957Y168452D01*
X337846Y168424D01*
X337721Y168382D01*
X337569Y168354D01*
X337416Y168313D01*
X337236Y168271D01*
X337042Y168230D01*
X336848Y168188D01*
X336626Y168160D01*
X336390Y168119D01*
X336362D01*
X336279Y168105D01*
X336140Y168077D01*
X335988Y168049D01*
X335821Y168022D01*
X335655Y167980D01*
X335503Y167938D01*
X335364Y167883D01*
X335350D01*
X335308Y167855D01*
X335253Y167827D01*
X335197Y167786D01*
X335031Y167675D01*
X334892Y167509D01*
Y167495D01*
X334865Y167467D01*
X334851Y167411D01*
X334823Y167342D01*
X334795Y167259D01*
X334767Y167176D01*
X334754Y167065D01*
X334740Y166954D01*
Y166940D01*
Y166871D01*
X334754Y166787D01*
X334781Y166677D01*
X334823Y166552D01*
X334892Y166427D01*
X334976Y166288D01*
X335086Y166163D01*
X335100Y166150D01*
X335156Y166122D01*
X335239Y166066D01*
X335350Y166011D01*
X335503Y165955D01*
X335683Y165900D01*
X335891Y165872D01*
X336140Y165858D01*
X336251D01*
X336390Y165872D01*
X336543Y165900D01*
X336737Y165928D01*
X336931Y165983D01*
X337139Y166052D01*
X337347Y166150D01*
X337375Y166163D01*
X337430Y166205D01*
X337527Y166274D01*
X337638Y166371D01*
X337763Y166482D01*
X337902Y166621D01*
X338013Y166787D01*
X338124Y166968D01*
X338137Y166982D01*
X338151Y167037D01*
X338179Y167134D01*
X338221Y167259D01*
X338262Y167425D01*
X338290Y167619D01*
X338304Y167855D01*
X338318Y168133D01*
X338332Y168576D01*
D02*
G37*
G36*
X327847Y173541D02*
X325628D01*
Y166219D01*
X327903D01*
X328000Y166233D01*
X328208Y166246D01*
X328443Y166260D01*
X328693Y166288D01*
X328943Y166330D01*
X329151Y166385D01*
X329179Y166399D01*
X329248Y166413D01*
X329345Y166455D01*
X329470Y166510D01*
X329608Y166593D01*
X329747Y166677D01*
X329886Y166773D01*
X330024Y166884D01*
X330038Y166912D01*
X330094Y166968D01*
X330177Y167065D01*
X330274Y167204D01*
X330385Y167384D01*
X330510Y167592D01*
X330621Y167827D01*
X330718Y168091D01*
Y168105D01*
X330732Y168133D01*
X330746Y168174D01*
X330760Y168230D01*
X330773Y168299D01*
X330801Y168396D01*
X330829Y168493D01*
X330857Y168604D01*
X330898Y168881D01*
X330940Y169200D01*
X330967Y169561D01*
X330981Y169949D01*
Y169963D01*
Y170019D01*
Y170088D01*
X330967Y170199D01*
Y170324D01*
X330954Y170462D01*
X330940Y170629D01*
X330926Y170795D01*
X330857Y171170D01*
X330773Y171558D01*
X330648Y171919D01*
X330565Y172099D01*
X330482Y172251D01*
Y172265D01*
X330454Y172293D01*
X330427Y172335D01*
X330399Y172390D01*
X330288Y172529D01*
X330149Y172695D01*
X329969Y172876D01*
X329761Y173056D01*
X329525Y173209D01*
X329276Y173333D01*
X329248Y173347D01*
X329179Y173361D01*
X329054Y173403D01*
X328873Y173444D01*
X328652Y173472D01*
X328374Y173514D01*
X328208Y173527D01*
X328027D01*
X327847Y173541D01*
D02*
G37*
G36*
X370312Y171225D02*
X370229D01*
X370173Y171211D01*
X370021Y171198D01*
X369841Y171156D01*
X369619Y171087D01*
X369383Y170989D01*
X369161Y170851D01*
X368939Y170671D01*
X368911Y170643D01*
X368856Y170574D01*
X368759Y170449D01*
X368662Y170282D01*
X368551Y170088D01*
X368454Y169839D01*
X368371Y169547D01*
X368329Y169228D01*
X372226D01*
Y169242D01*
Y169270D01*
X372212Y169312D01*
Y169367D01*
X372184Y169533D01*
X372143Y169714D01*
X372073Y169936D01*
X372004Y170144D01*
X371893Y170352D01*
X371768Y170532D01*
Y170546D01*
X371741Y170560D01*
X371671Y170643D01*
X371546Y170754D01*
X371380Y170879D01*
X371172Y171003D01*
X370922Y171114D01*
X370631Y171198D01*
X370479Y171211D01*
X370312Y171225D01*
D02*
G37*
G36*
X314395Y173749D02*
X314270D01*
X314173Y173736D01*
X314048Y173722D01*
X313923Y173694D01*
X313771Y173666D01*
X313604Y173638D01*
X313244Y173527D01*
X313050Y173444D01*
X312855Y173361D01*
X312647Y173250D01*
X312453Y173125D01*
X312259Y172987D01*
X312079Y172820D01*
X312065Y172806D01*
X312037Y172778D01*
X311996Y172723D01*
X311926Y172640D01*
X311857Y172543D01*
X311774Y172418D01*
X311690Y172265D01*
X311593Y172085D01*
X311510Y171891D01*
X311413Y171655D01*
X311330Y171406D01*
X311261Y171128D01*
X311191Y170823D01*
X311150Y170476D01*
X311122Y170116D01*
X311108Y169727D01*
Y169714D01*
Y169658D01*
Y169561D01*
X311122Y169436D01*
X311136Y169298D01*
X311163Y169131D01*
X311191Y168937D01*
X311219Y168743D01*
X311330Y168299D01*
X311413Y168077D01*
X311496Y167841D01*
X311607Y167619D01*
X311732Y167398D01*
X311871Y167190D01*
X312037Y166995D01*
X312051Y166982D01*
X312079Y166954D01*
X312134Y166898D01*
X312204Y166843D01*
X312301Y166760D01*
X312412Y166677D01*
X312536Y166593D01*
X312675Y166496D01*
X312841Y166399D01*
X313022Y166316D01*
X313216Y166233D01*
X313424Y166150D01*
X313646Y166094D01*
X313868Y166038D01*
X314117Y166011D01*
X314381Y165997D01*
X314450D01*
X314520Y166011D01*
X314617D01*
X314741Y166025D01*
X314880Y166052D01*
X315047Y166080D01*
X315213Y166122D01*
X315407Y166177D01*
X315587Y166246D01*
X315795Y166316D01*
X315990Y166413D01*
X316184Y166538D01*
X316378Y166663D01*
X316572Y166815D01*
X316752Y166995D01*
X316766Y167009D01*
X316794Y167037D01*
X316836Y167106D01*
X316905Y167190D01*
X316974Y167287D01*
X317044Y167411D01*
X317127Y167564D01*
X317224Y167730D01*
X317307Y167925D01*
X317390Y168146D01*
X317460Y168382D01*
X317543Y168632D01*
X317598Y168909D01*
X317640Y169214D01*
X317668Y169533D01*
X317682Y169866D01*
Y169880D01*
Y169922D01*
Y169977D01*
Y170060D01*
X317668Y170157D01*
Y170282D01*
X317654Y170407D01*
X317626Y170560D01*
X317584Y170879D01*
X317515Y171211D01*
X317418Y171572D01*
X317279Y171905D01*
Y171919D01*
X317265Y171946D01*
X317238Y171988D01*
X317210Y172043D01*
X317113Y172210D01*
X316988Y172404D01*
X316822Y172626D01*
X316614Y172848D01*
X316378Y173070D01*
X316114Y173264D01*
X316101D01*
X316087Y173292D01*
X316045Y173305D01*
X315976Y173347D01*
X315906Y173375D01*
X315823Y173417D01*
X315615Y173514D01*
X315366Y173597D01*
X315074Y173680D01*
X314741Y173736D01*
X314395Y173749D01*
D02*
G37*
G36*
X285340D02*
X285216D01*
X285119Y173736D01*
X284994Y173722D01*
X284869Y173694D01*
X284716Y173666D01*
X284550Y173638D01*
X284189Y173527D01*
X283995Y173444D01*
X283801Y173361D01*
X283593Y173250D01*
X283399Y173125D01*
X283205Y172987D01*
X283024Y172820D01*
X283011Y172806D01*
X282983Y172778D01*
X282941Y172723D01*
X282872Y172640D01*
X282803Y172543D01*
X282719Y172418D01*
X282636Y172265D01*
X282539Y172085D01*
X282456Y171891D01*
X282359Y171655D01*
X282276Y171406D01*
X282206Y171128D01*
X282137Y170823D01*
X282095Y170476D01*
X282068Y170116D01*
X282054Y169727D01*
Y169714D01*
Y169658D01*
Y169561D01*
X282068Y169436D01*
X282081Y169298D01*
X282109Y169131D01*
X282137Y168937D01*
X282165Y168743D01*
X282276Y168299D01*
X282359Y168077D01*
X282442Y167841D01*
X282553Y167619D01*
X282678Y167398D01*
X282816Y167190D01*
X282983Y166995D01*
X282997Y166982D01*
X283024Y166954D01*
X283080Y166898D01*
X283149Y166843D01*
X283246Y166760D01*
X283357Y166677D01*
X283482Y166593D01*
X283621Y166496D01*
X283787Y166399D01*
X283967Y166316D01*
X284162Y166233D01*
X284370Y166150D01*
X284592Y166094D01*
X284813Y166038D01*
X285063Y166011D01*
X285327Y165997D01*
X285396D01*
X285465Y166011D01*
X285562D01*
X285687Y166025D01*
X285826Y166052D01*
X285992Y166080D01*
X286159Y166122D01*
X286353Y166177D01*
X286533Y166246D01*
X286741Y166316D01*
X286935Y166413D01*
X287129Y166538D01*
X287324Y166663D01*
X287518Y166815D01*
X287698Y166995D01*
X287712Y167009D01*
X287740Y167037D01*
X287781Y167106D01*
X287851Y167190D01*
X287920Y167287D01*
X287989Y167411D01*
X288072Y167564D01*
X288170Y167730D01*
X288253Y167925D01*
X288336Y168146D01*
X288405Y168382D01*
X288489Y168632D01*
X288544Y168909D01*
X288586Y169214D01*
X288613Y169533D01*
X288627Y169866D01*
Y169880D01*
Y169922D01*
Y169977D01*
Y170060D01*
X288613Y170157D01*
Y170282D01*
X288599Y170407D01*
X288572Y170560D01*
X288530Y170879D01*
X288461Y171211D01*
X288364Y171572D01*
X288225Y171905D01*
Y171919D01*
X288211Y171946D01*
X288183Y171988D01*
X288156Y172043D01*
X288059Y172210D01*
X287934Y172404D01*
X287767Y172626D01*
X287559Y172848D01*
X287324Y173070D01*
X287060Y173264D01*
X287046D01*
X287032Y173292D01*
X286991Y173305D01*
X286921Y173347D01*
X286852Y173375D01*
X286769Y173417D01*
X286561Y173514D01*
X286311Y173597D01*
X286020Y173680D01*
X285687Y173736D01*
X285340Y173749D01*
D02*
G37*
G36*
X351590Y171225D02*
X351368D01*
X351312Y171211D01*
X351160Y171197D01*
X350980Y171142D01*
X350758Y171073D01*
X350536Y170948D01*
X350314Y170795D01*
X350203Y170684D01*
X350092Y170574D01*
Y170560D01*
X350064Y170546D01*
X350037Y170504D01*
X350009Y170449D01*
X349967Y170393D01*
X349926Y170310D01*
X349870Y170213D01*
X349828Y170102D01*
X349773Y169977D01*
X349718Y169825D01*
X349676Y169672D01*
X349634Y169506D01*
X349607Y169311D01*
X349579Y169117D01*
X349551Y168909D01*
Y168673D01*
Y168660D01*
Y168618D01*
Y168549D01*
X349565Y168452D01*
Y168341D01*
X349579Y168202D01*
X349621Y167911D01*
X349690Y167578D01*
X349773Y167259D01*
X349912Y166940D01*
X349995Y166801D01*
X350092Y166677D01*
X350120Y166649D01*
X350189Y166579D01*
X350300Y166482D01*
X350466Y166371D01*
X350661Y166246D01*
X350896Y166150D01*
X351160Y166080D01*
X351299Y166066D01*
X351451Y166052D01*
X351534D01*
X351590Y166066D01*
X351742Y166080D01*
X351936Y166136D01*
X352145Y166205D01*
X352380Y166316D01*
X352602Y166468D01*
X352713Y166565D01*
X352824Y166677D01*
Y166690D01*
X352852Y166704D01*
X352880Y166746D01*
X352907Y166801D01*
X352949Y166857D01*
X353004Y166940D01*
X353046Y167037D01*
X353102Y167162D01*
X353157Y167287D01*
X353199Y167425D01*
X353254Y167592D01*
X353296Y167772D01*
X353323Y167952D01*
X353351Y168160D01*
X353379Y168396D01*
Y168632D01*
Y168646D01*
Y168687D01*
Y168757D01*
X353365Y168840D01*
Y168951D01*
X353351Y169076D01*
X353310Y169353D01*
X353240Y169672D01*
X353143Y169991D01*
X353004Y170310D01*
X352907Y170449D01*
X352810Y170574D01*
Y170587D01*
X352783Y170601D01*
X352713Y170671D01*
X352588Y170781D01*
X352422Y170906D01*
X352228Y171017D01*
X351992Y171128D01*
X351729Y171197D01*
X351590Y171225D01*
D02*
G37*
G36*
X293967Y158433D02*
X290943Y154134D01*
X293967D01*
Y158433D01*
D02*
G37*
G36*
X370390Y492701D02*
X370307D01*
X370252Y492687D01*
X370113Y492673D01*
X369919Y492631D01*
X369711Y492562D01*
X369475Y492451D01*
X369253Y492312D01*
X369031Y492118D01*
X369004Y492090D01*
X368948Y492021D01*
X368851Y491896D01*
X368754Y491716D01*
X368657Y491508D01*
X368560Y491245D01*
X368504Y490953D01*
X368477Y490620D01*
Y490593D01*
Y490523D01*
X368490Y490399D01*
X368504Y490246D01*
X368532Y490066D01*
X368587Y489872D01*
X368643Y489664D01*
X368726Y489455D01*
X368740Y489428D01*
X368782Y489358D01*
X368837Y489261D01*
X368920Y489137D01*
X369017Y489012D01*
X369142Y488859D01*
X369281Y488734D01*
X369447Y488610D01*
X369475Y488596D01*
X369531Y488568D01*
X369628Y488512D01*
X369752Y488471D01*
X369891Y488415D01*
X370058Y488360D01*
X370238Y488332D01*
X370432Y488318D01*
X370501D01*
X370557Y488332D01*
X370695Y488346D01*
X370876Y488388D01*
X371070Y488471D01*
X371292Y488568D01*
X371514Y488721D01*
X371625Y488804D01*
X371722Y488915D01*
Y488928D01*
X371749Y488942D01*
X371805Y489026D01*
X371888Y489164D01*
X371999Y489345D01*
X372096Y489580D01*
X372179Y489858D01*
X372235Y490177D01*
X372263Y490551D01*
Y490565D01*
Y490593D01*
Y490648D01*
X372249Y490718D01*
Y490801D01*
X372235Y490898D01*
X372193Y491120D01*
X372138Y491369D01*
X372041Y491633D01*
X371902Y491883D01*
X371722Y492118D01*
X371694Y492146D01*
X371625Y492215D01*
X371514Y492299D01*
X371361Y492410D01*
X371167Y492520D01*
X370945Y492604D01*
X370682Y492673D01*
X370390Y492701D01*
D02*
G37*
G36*
X354830Y496043D02*
X351807D01*
Y492867D01*
X354664D01*
X354830Y492881D01*
X355024Y492895D01*
X355246Y492909D01*
X355468Y492937D01*
X355690Y492978D01*
X355884Y493034D01*
X355912Y493047D01*
X355967Y493075D01*
X356050Y493117D01*
X356161Y493172D01*
X356286Y493256D01*
X356411Y493353D01*
X356536Y493477D01*
X356633Y493616D01*
X356647Y493630D01*
X356674Y493685D01*
X356716Y493769D01*
X356772Y493880D01*
X356813Y494004D01*
X356855Y494143D01*
X356883Y494310D01*
X356896Y494476D01*
Y494490D01*
Y494504D01*
X356883Y494587D01*
X356869Y494712D01*
X356841Y494878D01*
X356772Y495045D01*
X356688Y495239D01*
X356564Y495419D01*
X356397Y495599D01*
X356369Y495613D01*
X356300Y495669D01*
X356189Y495738D01*
X356009Y495821D01*
X355801Y495904D01*
X355523Y495974D01*
X355205Y496029D01*
X354830Y496043D01*
D02*
G37*
G36*
X382545D02*
X379522D01*
Y492867D01*
X382379D01*
X382545Y492881D01*
X382739Y492895D01*
X382961Y492909D01*
X383183Y492937D01*
X383405Y492978D01*
X383599Y493034D01*
X383627Y493047D01*
X383683Y493075D01*
X383766Y493117D01*
X383877Y493172D01*
X384002Y493256D01*
X384126Y493353D01*
X384251Y493477D01*
X384348Y493616D01*
X384362Y493630D01*
X384390Y493685D01*
X384431Y493769D01*
X384487Y493880D01*
X384529Y494004D01*
X384570Y494143D01*
X384598Y494310D01*
X384612Y494476D01*
Y494490D01*
Y494504D01*
X384598Y494587D01*
X384584Y494712D01*
X384556Y494878D01*
X384487Y495045D01*
X384404Y495239D01*
X384279Y495419D01*
X384113Y495599D01*
X384085Y495613D01*
X384015Y495669D01*
X383904Y495738D01*
X383724Y495821D01*
X383516Y495904D01*
X383239Y495974D01*
X382920Y496029D01*
X382545Y496043D01*
D02*
G37*
G36*
X314725Y407647D02*
X314711D01*
X314697Y407634D01*
X314656Y407620D01*
X314600Y407606D01*
X314531Y407578D01*
X314448Y407550D01*
X314351Y407523D01*
X314240Y407495D01*
X314115Y407453D01*
X313962Y407425D01*
X313810Y407384D01*
X313629Y407342D01*
X313435Y407301D01*
X313241Y407259D01*
X313019Y407231D01*
X312784Y407190D01*
X312756D01*
X312673Y407176D01*
X312534Y407148D01*
X312381Y407120D01*
X312215Y407093D01*
X312049Y407051D01*
X311896Y407009D01*
X311757Y406954D01*
X311743D01*
X311702Y406926D01*
X311646Y406898D01*
X311591Y406857D01*
X311425Y406746D01*
X311286Y406580D01*
Y406566D01*
X311258Y406538D01*
X311244Y406482D01*
X311216Y406413D01*
X311189Y406330D01*
X311161Y406247D01*
X311147Y406136D01*
X311133Y406025D01*
Y406011D01*
Y405942D01*
X311147Y405858D01*
X311175Y405747D01*
X311216Y405623D01*
X311286Y405498D01*
X311369Y405359D01*
X311480Y405234D01*
X311494Y405220D01*
X311549Y405193D01*
X311632Y405137D01*
X311743Y405082D01*
X311896Y405026D01*
X312076Y404971D01*
X312284Y404943D01*
X312534Y404929D01*
X312645D01*
X312784Y404943D01*
X312936Y404971D01*
X313130Y404999D01*
X313324Y405054D01*
X313533Y405123D01*
X313741Y405220D01*
X313768Y405234D01*
X313824Y405276D01*
X313921Y405345D01*
X314032Y405442D01*
X314156Y405553D01*
X314295Y405692D01*
X314406Y405858D01*
X314517Y406039D01*
X314531Y406053D01*
X314545Y406108D01*
X314573Y406205D01*
X314614Y406330D01*
X314656Y406496D01*
X314683Y406690D01*
X314697Y406926D01*
X314711Y407204D01*
X314725Y407647D01*
D02*
G37*
G36*
X292827Y412751D02*
Y412737D01*
X292813Y412709D01*
Y412654D01*
X292785Y412598D01*
X292771Y412501D01*
X292744Y412404D01*
X292688Y412169D01*
X292619Y411891D01*
X292522Y411586D01*
X292425Y411253D01*
X292300Y410906D01*
X291260Y408105D01*
X294505D01*
X293507Y410740D01*
Y410754D01*
X293493Y410796D01*
X293465Y410865D01*
X293437Y410948D01*
X293396Y411045D01*
X293354Y411170D01*
X293312Y411309D01*
X293257Y411447D01*
X293146Y411766D01*
X293035Y412099D01*
X292924Y412432D01*
X292827Y412751D01*
D02*
G37*
G36*
X327262Y410296D02*
X327179D01*
X327110Y410282D01*
X326957Y410269D01*
X326749Y410213D01*
X326513Y410130D01*
X326264Y410019D01*
X326028Y409852D01*
X325903Y409742D01*
X325792Y409631D01*
Y409617D01*
X325764Y409603D01*
X325737Y409561D01*
X325695Y409506D01*
X325653Y409436D01*
X325612Y409353D01*
X325556Y409242D01*
X325501Y409131D01*
X325445Y408993D01*
X325390Y408854D01*
X325348Y408688D01*
X325307Y408507D01*
X325265Y408313D01*
X325237Y408105D01*
X325224Y407869D01*
X325210Y407634D01*
Y407620D01*
Y407578D01*
Y407509D01*
X325224Y407412D01*
Y407301D01*
X325237Y407176D01*
X325279Y406885D01*
X325348Y406552D01*
X325459Y406219D01*
X325598Y405900D01*
X325695Y405761D01*
X325792Y405623D01*
X325806D01*
X325820Y405595D01*
X325903Y405526D01*
X326028Y405415D01*
X326194Y405304D01*
X326402Y405179D01*
X326652Y405068D01*
X326943Y404999D01*
X327096Y404985D01*
X327262Y404971D01*
X327345D01*
X327415Y404985D01*
X327567Y405012D01*
X327775Y405054D01*
X327997Y405137D01*
X328247Y405248D01*
X328483Y405415D01*
X328607Y405526D01*
X328718Y405636D01*
X328732Y405650D01*
X328746Y405664D01*
X328774Y405706D01*
X328815Y405761D01*
X328857Y405831D01*
X328913Y405914D01*
X328968Y406025D01*
X329024Y406136D01*
X329079Y406274D01*
X329121Y406427D01*
X329176Y406593D01*
X329218Y406774D01*
X329259Y406982D01*
X329287Y407190D01*
X329315Y407425D01*
Y407675D01*
Y407689D01*
Y407731D01*
Y407800D01*
X329301Y407883D01*
Y407994D01*
X329287Y408119D01*
X329245Y408410D01*
X329176Y408715D01*
X329065Y409048D01*
X328913Y409353D01*
X328829Y409506D01*
X328718Y409631D01*
Y409644D01*
X328691Y409658D01*
X328607Y409742D01*
X328483Y409839D01*
X328316Y409963D01*
X328108Y410088D01*
X327859Y410199D01*
X327581Y410269D01*
X327429Y410282D01*
X327262Y410296D01*
D02*
G37*
G36*
X301425D02*
X301217D01*
X301162Y410282D01*
X301009Y410255D01*
X300829Y410213D01*
X300621Y410130D01*
X300399Y410005D01*
X300288Y409936D01*
X300177Y409839D01*
X300066Y409742D01*
X299955Y409617D01*
Y409603D01*
X299928Y409589D01*
X299900Y409547D01*
X299872Y409492D01*
X299830Y409422D01*
X299775Y409339D01*
X299733Y409242D01*
X299678Y409131D01*
X299622Y408993D01*
X299581Y408854D01*
X299525Y408688D01*
X299484Y408521D01*
X299456Y408327D01*
X299428Y408119D01*
X299401Y407911D01*
Y407675D01*
Y407661D01*
Y407620D01*
Y407550D01*
Y407467D01*
X299414Y407370D01*
Y407245D01*
X299442Y406982D01*
X299484Y406690D01*
X299539Y406385D01*
X299622Y406108D01*
X299678Y405983D01*
X299733Y405872D01*
Y405858D01*
X299761Y405831D01*
X299789Y405789D01*
X299830Y405734D01*
X299955Y405581D01*
X300136Y405428D01*
X300344Y405262D01*
X300607Y405109D01*
X300746Y405054D01*
X300912Y405012D01*
X301065Y404985D01*
X301245Y404971D01*
X301314D01*
X301370Y404985D01*
X301522Y405012D01*
X301703Y405054D01*
X301911Y405137D01*
X302133Y405248D01*
X302355Y405415D01*
X302465Y405526D01*
X302576Y405636D01*
Y405650D01*
X302604Y405664D01*
X302632Y405706D01*
X302660Y405761D01*
X302715Y405831D01*
X302757Y405914D01*
X302812Y406025D01*
X302868Y406136D01*
X302909Y406274D01*
X302965Y406413D01*
X303020Y406580D01*
X303062Y406760D01*
X303090Y406954D01*
X303117Y407162D01*
X303145Y407398D01*
Y407634D01*
Y407647D01*
Y407689D01*
Y407758D01*
X303131Y407855D01*
Y407966D01*
X303117Y408105D01*
X303076Y408396D01*
X303020Y408715D01*
X302923Y409062D01*
X302785Y409367D01*
X302701Y409520D01*
X302604Y409644D01*
Y409658D01*
X302576Y409672D01*
X302507Y409742D01*
X302396Y409852D01*
X302244Y409977D01*
X302049Y410088D01*
X301828Y410199D01*
X301564Y410269D01*
X301425Y410296D01*
D02*
G37*
G36*
X360715Y347397D02*
X360702D01*
X360688Y347383D01*
X360646Y347370D01*
X360591Y347356D01*
X360521Y347328D01*
X360438Y347300D01*
X360341Y347273D01*
X360230Y347245D01*
X360105Y347203D01*
X359953Y347175D01*
X359800Y347134D01*
X359620Y347092D01*
X359426Y347051D01*
X359232Y347009D01*
X359010Y346981D01*
X358774Y346940D01*
X358746D01*
X358663Y346926D01*
X358524Y346898D01*
X358372Y346870D01*
X358205Y346843D01*
X358039Y346801D01*
X357886Y346759D01*
X357748Y346704D01*
X357734D01*
X357692Y346676D01*
X357637Y346648D01*
X357581Y346607D01*
X357415Y346496D01*
X357276Y346329D01*
Y346316D01*
X357248Y346288D01*
X357234Y346232D01*
X357207Y346163D01*
X357179Y346080D01*
X357151Y345997D01*
X357137Y345886D01*
X357124Y345775D01*
Y345761D01*
Y345692D01*
X357137Y345608D01*
X357165Y345497D01*
X357207Y345373D01*
X357276Y345248D01*
X357359Y345109D01*
X357470Y344984D01*
X357484Y344970D01*
X357540Y344943D01*
X357623Y344887D01*
X357734Y344832D01*
X357886Y344776D01*
X358067Y344721D01*
X358275Y344693D01*
X358524Y344679D01*
X358635D01*
X358774Y344693D01*
X358927Y344721D01*
X359121Y344748D01*
X359315Y344804D01*
X359523Y344873D01*
X359731Y344970D01*
X359759Y344984D01*
X359814Y345026D01*
X359911Y345095D01*
X360022Y345192D01*
X360147Y345303D01*
X360286Y345442D01*
X360396Y345608D01*
X360508Y345789D01*
X360521Y345802D01*
X360535Y345858D01*
X360563Y345955D01*
X360605Y346080D01*
X360646Y346246D01*
X360674Y346441D01*
X360688Y346676D01*
X360702Y346954D01*
X360715Y347397D01*
D02*
G37*
G36*
X351049Y352432D02*
X348026D01*
Y349256D01*
X350883D01*
X351049Y349270D01*
X351243Y349283D01*
X351465Y349297D01*
X351687Y349325D01*
X351909Y349367D01*
X352103Y349422D01*
X352131Y349436D01*
X352186Y349464D01*
X352270Y349505D01*
X352381Y349561D01*
X352505Y349644D01*
X352630Y349741D01*
X352755Y349866D01*
X352852Y350005D01*
X352866Y350019D01*
X352894Y350074D01*
X352935Y350157D01*
X352991Y350268D01*
X353032Y350393D01*
X353074Y350532D01*
X353102Y350698D01*
X353116Y350864D01*
Y350878D01*
Y350892D01*
X353102Y350975D01*
X353088Y351100D01*
X353060Y351267D01*
X352991Y351433D01*
X352908Y351627D01*
X352783Y351808D01*
X352616Y351988D01*
X352589Y352002D01*
X352519Y352057D01*
X352408Y352127D01*
X352228Y352210D01*
X352020Y352293D01*
X351743Y352362D01*
X351424Y352418D01*
X351049Y352432D01*
D02*
G37*
G36*
X373252Y350046D02*
X373169D01*
X373100Y350032D01*
X372947Y350019D01*
X372739Y349963D01*
X372504Y349880D01*
X372254Y349769D01*
X372018Y349603D01*
X371893Y349492D01*
X371782Y349381D01*
Y349367D01*
X371755Y349353D01*
X371727Y349311D01*
X371685Y349256D01*
X371644Y349186D01*
X371602Y349103D01*
X371547Y348992D01*
X371491Y348881D01*
X371436Y348743D01*
X371380Y348604D01*
X371339Y348438D01*
X371297Y348257D01*
X371255Y348063D01*
X371228Y347855D01*
X371214Y347619D01*
X371200Y347383D01*
Y347370D01*
Y347328D01*
Y347259D01*
X371214Y347162D01*
Y347051D01*
X371228Y346926D01*
X371269Y346635D01*
X371339Y346302D01*
X371450Y345969D01*
X371588Y345650D01*
X371685Y345511D01*
X371782Y345373D01*
X371796D01*
X371810Y345345D01*
X371893Y345275D01*
X372018Y345165D01*
X372185Y345054D01*
X372393Y344929D01*
X372642Y344818D01*
X372934Y344748D01*
X373086Y344735D01*
X373252Y344721D01*
X373336D01*
X373405Y344735D01*
X373558Y344762D01*
X373766Y344804D01*
X373988Y344887D01*
X374237Y344998D01*
X374473Y345165D01*
X374598Y345275D01*
X374709Y345387D01*
X374723Y345400D01*
X374736Y345414D01*
X374764Y345456D01*
X374806Y345511D01*
X374847Y345581D01*
X374903Y345664D01*
X374958Y345775D01*
X375014Y345886D01*
X375069Y346024D01*
X375111Y346177D01*
X375166Y346343D01*
X375208Y346524D01*
X375250Y346732D01*
X375277Y346940D01*
X375305Y347175D01*
Y347425D01*
Y347439D01*
Y347481D01*
Y347550D01*
X375291Y347633D01*
Y347744D01*
X375277Y347869D01*
X375236Y348160D01*
X375166Y348465D01*
X375055Y348798D01*
X374903Y349103D01*
X374820Y349256D01*
X374709Y349381D01*
Y349394D01*
X374681Y349408D01*
X374598Y349492D01*
X374473Y349589D01*
X374306Y349713D01*
X374099Y349838D01*
X373849Y349949D01*
X373572Y350019D01*
X373419Y350032D01*
X373252Y350046D01*
D02*
G37*
G36*
X232167Y375810D02*
X232084D01*
X232028Y375796D01*
X231876Y375782D01*
X231695Y375741D01*
X231474Y375671D01*
X231238Y375574D01*
X231016Y375436D01*
X230794Y375255D01*
X230766Y375228D01*
X230711Y375158D01*
X230614Y375033D01*
X230517Y374867D01*
X230406Y374673D01*
X230309Y374423D01*
X230225Y374132D01*
X230184Y373813D01*
X234081D01*
Y373827D01*
Y373855D01*
X234067Y373896D01*
Y373952D01*
X234039Y374118D01*
X233998Y374299D01*
X233928Y374520D01*
X233859Y374728D01*
X233748Y374936D01*
X233623Y375117D01*
Y375131D01*
X233595Y375144D01*
X233526Y375228D01*
X233401Y375339D01*
X233235Y375463D01*
X233027Y375588D01*
X232777Y375699D01*
X232486Y375782D01*
X232333Y375796D01*
X232167Y375810D01*
D02*
G37*
G36*
X59830Y359241D02*
X56807D01*
Y356065D01*
X59664D01*
X59830Y356079D01*
X60025Y356093D01*
X60247Y356107D01*
X60468Y356134D01*
X60690Y356176D01*
X60884Y356231D01*
X60912Y356245D01*
X60968Y356273D01*
X61051Y356315D01*
X61162Y356370D01*
X61287Y356453D01*
X61411Y356550D01*
X61536Y356675D01*
X61633Y356814D01*
X61647Y356828D01*
X61675Y356883D01*
X61716Y356967D01*
X61772Y357077D01*
X61814Y357202D01*
X61855Y357341D01*
X61883Y357507D01*
X61897Y357674D01*
Y357688D01*
Y357701D01*
X61883Y357785D01*
X61869Y357910D01*
X61841Y358076D01*
X61772Y358242D01*
X61689Y358437D01*
X61564Y358617D01*
X61398Y358797D01*
X61370Y358811D01*
X61301Y358867D01*
X61189Y358936D01*
X61009Y359019D01*
X60801Y359102D01*
X60524Y359172D01*
X60205Y359227D01*
X59830Y359241D01*
D02*
G37*
G36*
X85806Y356856D02*
X85723D01*
X85667Y356842D01*
X85515Y356828D01*
X85334Y356786D01*
X85112Y356717D01*
X84877Y356620D01*
X84655Y356481D01*
X84433Y356301D01*
X84405Y356273D01*
X84350Y356204D01*
X84253Y356079D01*
X84156Y355913D01*
X84045Y355718D01*
X83948Y355469D01*
X83864Y355177D01*
X83823Y354859D01*
X87720D01*
Y354872D01*
Y354900D01*
X87706Y354942D01*
Y354997D01*
X87678Y355164D01*
X87637Y355344D01*
X87567Y355566D01*
X87498Y355774D01*
X87387Y355982D01*
X87262Y356162D01*
Y356176D01*
X87234Y356190D01*
X87165Y356273D01*
X87040Y356384D01*
X86874Y356509D01*
X86666Y356634D01*
X86416Y356745D01*
X86125Y356828D01*
X85972Y356842D01*
X85806Y356856D01*
D02*
G37*
G36*
X75585D02*
X75377D01*
X75321Y356842D01*
X75169Y356814D01*
X74989Y356772D01*
X74781Y356689D01*
X74559Y356564D01*
X74448Y356495D01*
X74337Y356398D01*
X74226Y356301D01*
X74115Y356176D01*
Y356162D01*
X74087Y356148D01*
X74059Y356107D01*
X74032Y356051D01*
X73990Y355982D01*
X73935Y355899D01*
X73893Y355802D01*
X73837Y355691D01*
X73782Y355552D01*
X73740Y355413D01*
X73685Y355247D01*
X73643Y355080D01*
X73616Y354886D01*
X73588Y354678D01*
X73560Y354470D01*
Y354234D01*
Y354221D01*
Y354179D01*
Y354110D01*
Y354026D01*
X73574Y353929D01*
Y353805D01*
X73602Y353541D01*
X73643Y353250D01*
X73699Y352945D01*
X73782Y352667D01*
X73837Y352542D01*
X73893Y352432D01*
Y352418D01*
X73921Y352390D01*
X73948Y352348D01*
X73990Y352293D01*
X74115Y352140D01*
X74295Y351988D01*
X74503Y351821D01*
X74767Y351669D01*
X74905Y351613D01*
X75072Y351572D01*
X75224Y351544D01*
X75405Y351530D01*
X75474D01*
X75529Y351544D01*
X75682Y351572D01*
X75862Y351613D01*
X76070Y351697D01*
X76292Y351808D01*
X76514Y351974D01*
X76625Y352085D01*
X76736Y352196D01*
Y352210D01*
X76764Y352224D01*
X76792Y352265D01*
X76819Y352321D01*
X76875Y352390D01*
X76916Y352473D01*
X76972Y352584D01*
X77027Y352695D01*
X77069Y352834D01*
X77124Y352972D01*
X77180Y353139D01*
X77221Y353319D01*
X77249Y353513D01*
X77277Y353721D01*
X77305Y353957D01*
Y354193D01*
Y354207D01*
Y354248D01*
Y354318D01*
X77291Y354415D01*
Y354526D01*
X77277Y354664D01*
X77235Y354956D01*
X77180Y355275D01*
X77083Y355621D01*
X76944Y355926D01*
X76861Y356079D01*
X76764Y356204D01*
Y356218D01*
X76736Y356231D01*
X76667Y356301D01*
X76556Y356412D01*
X76403Y356537D01*
X76209Y356647D01*
X75987Y356758D01*
X75724Y356828D01*
X75585Y356856D01*
D02*
G37*
G36*
X67860D02*
X67777D01*
X67708Y356842D01*
X67555Y356828D01*
X67347Y356772D01*
X67111Y356689D01*
X66862Y356578D01*
X66626Y356412D01*
X66501Y356301D01*
X66390Y356190D01*
Y356176D01*
X66363Y356162D01*
X66335Y356120D01*
X66293Y356065D01*
X66252Y355996D01*
X66210Y355913D01*
X66154Y355802D01*
X66099Y355691D01*
X66044Y355552D01*
X65988Y355413D01*
X65946Y355247D01*
X65905Y355066D01*
X65863Y354872D01*
X65835Y354664D01*
X65822Y354429D01*
X65808Y354193D01*
Y354179D01*
Y354137D01*
Y354068D01*
X65822Y353971D01*
Y353860D01*
X65835Y353735D01*
X65877Y353444D01*
X65946Y353111D01*
X66057Y352778D01*
X66196Y352459D01*
X66293Y352321D01*
X66390Y352182D01*
X66404D01*
X66418Y352154D01*
X66501Y352085D01*
X66626Y351974D01*
X66792Y351863D01*
X67000Y351738D01*
X67250Y351627D01*
X67541Y351558D01*
X67694Y351544D01*
X67860Y351530D01*
X67944D01*
X68013Y351544D01*
X68165Y351572D01*
X68373Y351613D01*
X68595Y351697D01*
X68845Y351808D01*
X69081Y351974D01*
X69205Y352085D01*
X69316Y352196D01*
X69330Y352210D01*
X69344Y352224D01*
X69372Y352265D01*
X69413Y352321D01*
X69455Y352390D01*
X69511Y352473D01*
X69566Y352584D01*
X69622Y352695D01*
X69677Y352834D01*
X69719Y352986D01*
X69774Y353153D01*
X69816Y353333D01*
X69857Y353541D01*
X69885Y353749D01*
X69913Y353985D01*
Y354234D01*
Y354248D01*
Y354290D01*
Y354359D01*
X69899Y354442D01*
Y354553D01*
X69885Y354678D01*
X69843Y354969D01*
X69774Y355275D01*
X69663Y355607D01*
X69511Y355913D01*
X69427Y356065D01*
X69316Y356190D01*
Y356204D01*
X69289Y356218D01*
X69205Y356301D01*
X69081Y356398D01*
X68914Y356523D01*
X68706Y356647D01*
X68457Y356758D01*
X68179Y356828D01*
X68027Y356842D01*
X67860Y356856D01*
D02*
G37*
G36*
X97573Y387147D02*
X97560D01*
X97546Y387133D01*
X97504Y387120D01*
X97449Y387106D01*
X97379Y387078D01*
X97296Y387050D01*
X97199Y387023D01*
X97088Y386995D01*
X96963Y386953D01*
X96811Y386926D01*
X96658Y386884D01*
X96478Y386842D01*
X96284Y386801D01*
X96089Y386759D01*
X95868Y386731D01*
X95632Y386690D01*
X95604D01*
X95521Y386676D01*
X95382Y386648D01*
X95230Y386620D01*
X95063Y386593D01*
X94897Y386551D01*
X94744Y386510D01*
X94606Y386454D01*
X94592D01*
X94550Y386426D01*
X94495Y386399D01*
X94439Y386357D01*
X94273Y386246D01*
X94134Y386079D01*
Y386066D01*
X94106Y386038D01*
X94093Y385983D01*
X94065Y385913D01*
X94037Y385830D01*
X94009Y385747D01*
X93995Y385636D01*
X93982Y385525D01*
Y385511D01*
Y385442D01*
X93995Y385358D01*
X94023Y385247D01*
X94065Y385123D01*
X94134Y384998D01*
X94217Y384859D01*
X94328Y384734D01*
X94342Y384720D01*
X94398Y384693D01*
X94481Y384637D01*
X94592Y384582D01*
X94744Y384526D01*
X94925Y384471D01*
X95133Y384443D01*
X95382Y384429D01*
X95493D01*
X95632Y384443D01*
X95784Y384471D01*
X95979Y384498D01*
X96173Y384554D01*
X96381Y384623D01*
X96589Y384720D01*
X96616Y384734D01*
X96672Y384776D01*
X96769Y384845D01*
X96880Y384942D01*
X97005Y385053D01*
X97143Y385192D01*
X97254Y385358D01*
X97365Y385539D01*
X97379Y385552D01*
X97393Y385608D01*
X97421Y385705D01*
X97463Y385830D01*
X97504Y385996D01*
X97532Y386190D01*
X97546Y386426D01*
X97560Y386704D01*
X97573Y387147D01*
D02*
G37*
G36*
X60281Y387147D02*
X60267D01*
X60254Y387133D01*
X60212Y387120D01*
X60156Y387106D01*
X60087Y387078D01*
X60004Y387050D01*
X59907Y387023D01*
X59796Y386995D01*
X59671Y386953D01*
X59518Y386926D01*
X59366Y386884D01*
X59186Y386842D01*
X58992Y386801D01*
X58797Y386759D01*
X58576Y386731D01*
X58340Y386690D01*
X58312D01*
X58229Y386676D01*
X58090Y386648D01*
X57938Y386620D01*
X57771Y386593D01*
X57605Y386551D01*
X57452Y386509D01*
X57313Y386454D01*
X57300D01*
X57258Y386426D01*
X57203Y386399D01*
X57147Y386357D01*
X56981Y386246D01*
X56842Y386079D01*
Y386066D01*
X56814Y386038D01*
X56800Y385982D01*
X56773Y385913D01*
X56745Y385830D01*
X56717Y385747D01*
X56703Y385636D01*
X56689Y385525D01*
Y385511D01*
Y385442D01*
X56703Y385358D01*
X56731Y385247D01*
X56773Y385123D01*
X56842Y384998D01*
X56925Y384859D01*
X57036Y384734D01*
X57050Y384720D01*
X57105Y384693D01*
X57189Y384637D01*
X57300Y384582D01*
X57452Y384526D01*
X57632Y384471D01*
X57840Y384443D01*
X58090Y384429D01*
X58201D01*
X58340Y384443D01*
X58492Y384471D01*
X58686Y384498D01*
X58881Y384554D01*
X59089Y384623D01*
X59297Y384720D01*
X59324Y384734D01*
X59380Y384776D01*
X59477Y384845D01*
X59588Y384942D01*
X59713Y385053D01*
X59851Y385192D01*
X59962Y385358D01*
X60073Y385539D01*
X60087Y385552D01*
X60101Y385608D01*
X60129Y385705D01*
X60170Y385830D01*
X60212Y385996D01*
X60240Y386190D01*
X60254Y386426D01*
X60267Y386704D01*
X60281Y387147D01*
D02*
G37*
G36*
X84787Y389796D02*
X84704D01*
X84648Y389782D01*
X84495Y389768D01*
X84315Y389727D01*
X84093Y389658D01*
X83858Y389561D01*
X83636Y389422D01*
X83414Y389241D01*
X83386Y389214D01*
X83331Y389144D01*
X83233Y389020D01*
X83136Y388853D01*
X83026Y388659D01*
X82928Y388409D01*
X82845Y388118D01*
X82804Y387799D01*
X86701D01*
Y387813D01*
Y387841D01*
X86687Y387882D01*
Y387938D01*
X86659Y388104D01*
X86617Y388285D01*
X86548Y388507D01*
X86479Y388714D01*
X86368Y388923D01*
X86243Y389103D01*
Y389117D01*
X86215Y389131D01*
X86146Y389214D01*
X86021Y389325D01*
X85855Y389450D01*
X85647Y389574D01*
X85397Y389685D01*
X85106Y389768D01*
X84953Y389782D01*
X84787Y389796D01*
D02*
G37*
G36*
X77547D02*
X77339D01*
X77284Y389782D01*
X77131Y389755D01*
X76951Y389713D01*
X76743Y389630D01*
X76521Y389505D01*
X76410Y389436D01*
X76299Y389339D01*
X76188Y389241D01*
X76077Y389117D01*
Y389103D01*
X76050Y389089D01*
X76022Y389047D01*
X75994Y388992D01*
X75953Y388923D01*
X75897Y388839D01*
X75855Y388742D01*
X75800Y388631D01*
X75745Y388493D01*
X75703Y388354D01*
X75648Y388187D01*
X75606Y388021D01*
X75578Y387827D01*
X75550Y387619D01*
X75523Y387411D01*
Y387175D01*
Y387161D01*
Y387120D01*
Y387050D01*
Y386967D01*
X75537Y386870D01*
Y386745D01*
X75564Y386482D01*
X75606Y386190D01*
X75661Y385885D01*
X75745Y385608D01*
X75800Y385483D01*
X75855Y385372D01*
Y385358D01*
X75883Y385331D01*
X75911Y385289D01*
X75953Y385233D01*
X76077Y385081D01*
X76258Y384928D01*
X76466Y384762D01*
X76729Y384609D01*
X76868Y384554D01*
X77034Y384512D01*
X77187Y384485D01*
X77367Y384471D01*
X77436D01*
X77492Y384485D01*
X77645Y384512D01*
X77825Y384554D01*
X78033Y384637D01*
X78255Y384748D01*
X78477Y384915D01*
X78588Y385025D01*
X78699Y385136D01*
Y385150D01*
X78726Y385164D01*
X78754Y385206D01*
X78782Y385261D01*
X78837Y385331D01*
X78879Y385414D01*
X78934Y385525D01*
X78990Y385636D01*
X79031Y385774D01*
X79087Y385913D01*
X79142Y386079D01*
X79184Y386260D01*
X79212Y386454D01*
X79239Y386662D01*
X79267Y386898D01*
Y387133D01*
Y387147D01*
Y387189D01*
Y387258D01*
X79253Y387355D01*
Y387466D01*
X79239Y387605D01*
X79198Y387896D01*
X79142Y388215D01*
X79045Y388562D01*
X78907Y388867D01*
X78823Y389020D01*
X78726Y389144D01*
Y389158D01*
X78699Y389172D01*
X78629Y389241D01*
X78518Y389352D01*
X78366Y389477D01*
X78172Y389588D01*
X77950Y389699D01*
X77686Y389768D01*
X77547Y389796D01*
D02*
G37*
G36*
X40033D02*
X39950D01*
X39895Y389782D01*
X39742Y389768D01*
X39562Y389727D01*
X39340Y389658D01*
X39104Y389561D01*
X38882Y389422D01*
X38661Y389241D01*
X38633Y389214D01*
X38577Y389144D01*
X38480Y389020D01*
X38383Y388853D01*
X38272Y388659D01*
X38175Y388409D01*
X38092Y388118D01*
X38050Y387799D01*
X41947D01*
Y387813D01*
Y387841D01*
X41933Y387882D01*
Y387938D01*
X41906Y388104D01*
X41864Y388285D01*
X41795Y388507D01*
X41725Y388714D01*
X41614Y388923D01*
X41490Y389103D01*
Y389117D01*
X41462Y389131D01*
X41393Y389214D01*
X41268Y389325D01*
X41101Y389450D01*
X40893Y389574D01*
X40644Y389685D01*
X40352Y389768D01*
X40200Y389782D01*
X40033Y389796D01*
D02*
G37*
G36*
X48054Y374209D02*
X47985D01*
X47929Y374195D01*
X47777Y374181D01*
X47597Y374126D01*
X47389Y374056D01*
X47167Y373932D01*
X46945Y373779D01*
X46834Y373668D01*
X46737Y373557D01*
Y373543D01*
X46709Y373529D01*
X46695Y373488D01*
X46653Y373432D01*
X46612Y373363D01*
X46570Y373280D01*
X46529Y373183D01*
X46473Y373072D01*
X46418Y372933D01*
X46376Y372780D01*
X46335Y372614D01*
X46293Y372434D01*
X46265Y372240D01*
X46237Y372018D01*
X46210Y371782D01*
Y371532D01*
Y371519D01*
Y371477D01*
Y371408D01*
X46224Y371311D01*
Y371199D01*
X46237Y371075D01*
X46279Y370784D01*
X46348Y370465D01*
X46445Y370132D01*
X46584Y369813D01*
X46667Y369674D01*
X46764Y369535D01*
X46778D01*
X46792Y369508D01*
X46862Y369438D01*
X46986Y369327D01*
X47139Y369216D01*
X47333Y369091D01*
X47569Y368981D01*
X47818Y368911D01*
X47957Y368897D01*
X48096Y368884D01*
X48165D01*
X48221Y368897D01*
X48373Y368911D01*
X48553Y368967D01*
X48761Y369036D01*
X48983Y369147D01*
X49205Y369300D01*
X49316Y369397D01*
X49413Y369508D01*
Y369521D01*
X49441Y369535D01*
X49469Y369577D01*
X49496Y369632D01*
X49538Y369702D01*
X49594Y369771D01*
X49635Y369882D01*
X49691Y369993D01*
X49746Y370118D01*
X49788Y370257D01*
X49843Y370423D01*
X49885Y370589D01*
X49913Y370784D01*
X49940Y370978D01*
X49968Y371199D01*
Y371435D01*
Y371449D01*
Y371505D01*
Y371574D01*
X49954Y371671D01*
Y371782D01*
X49940Y371921D01*
X49926Y372073D01*
X49899Y372240D01*
X49829Y372573D01*
X49732Y372919D01*
X49594Y373252D01*
X49510Y373391D01*
X49413Y373529D01*
Y373543D01*
X49385Y373557D01*
X49316Y373640D01*
X49191Y373751D01*
X49039Y373876D01*
X48845Y374001D01*
X48609Y374098D01*
X48345Y374181D01*
X48207Y374195D01*
X48054Y374209D01*
D02*
G37*
G36*
X76748Y371560D02*
X76734D01*
X76720Y371546D01*
X76679Y371532D01*
X76623Y371519D01*
X76554Y371491D01*
X76470Y371463D01*
X76373Y371435D01*
X76262Y371408D01*
X76138Y371366D01*
X75985Y371338D01*
X75833Y371297D01*
X75652Y371255D01*
X75458Y371213D01*
X75264Y371172D01*
X75042Y371144D01*
X74806Y371102D01*
X74779D01*
X74695Y371089D01*
X74557Y371061D01*
X74404Y371033D01*
X74238Y371005D01*
X74071Y370964D01*
X73919Y370922D01*
X73780Y370867D01*
X73766D01*
X73725Y370839D01*
X73669Y370811D01*
X73614Y370770D01*
X73447Y370659D01*
X73309Y370492D01*
Y370478D01*
X73281Y370451D01*
X73267Y370395D01*
X73239Y370326D01*
X73211Y370243D01*
X73184Y370159D01*
X73170Y370048D01*
X73156Y369938D01*
Y369924D01*
Y369854D01*
X73170Y369771D01*
X73198Y369660D01*
X73239Y369535D01*
X73309Y369411D01*
X73392Y369272D01*
X73503Y369147D01*
X73517Y369133D01*
X73572Y369105D01*
X73655Y369050D01*
X73766Y368994D01*
X73919Y368939D01*
X74099Y368884D01*
X74307Y368856D01*
X74557Y368842D01*
X74668D01*
X74806Y368856D01*
X74959Y368884D01*
X75153Y368911D01*
X75347Y368967D01*
X75555Y369036D01*
X75763Y369133D01*
X75791Y369147D01*
X75846Y369189D01*
X75943Y369258D01*
X76055Y369355D01*
X76179Y369466D01*
X76318Y369605D01*
X76429Y369771D01*
X76540Y369951D01*
X76554Y369965D01*
X76568Y370021D01*
X76595Y370118D01*
X76637Y370243D01*
X76679Y370409D01*
X76706Y370603D01*
X76720Y370839D01*
X76734Y371116D01*
X76748Y371560D01*
D02*
G37*
G36*
X60286Y376525D02*
X58012D01*
Y373640D01*
X60369D01*
X60550Y373654D01*
X60744Y373668D01*
X60938Y373682D01*
X61132Y373710D01*
X61285Y373737D01*
X61312Y373751D01*
X61368Y373765D01*
X61451Y373807D01*
X61562Y373862D01*
X61673Y373918D01*
X61798Y374001D01*
X61923Y374112D01*
X62020Y374223D01*
X62034Y374237D01*
X62061Y374278D01*
X62103Y374361D01*
X62144Y374459D01*
X62186Y374570D01*
X62228Y374708D01*
X62255Y374875D01*
X62269Y375055D01*
Y375083D01*
Y375138D01*
X62255Y375221D01*
X62242Y375332D01*
X62214Y375471D01*
X62172Y375610D01*
X62117Y375748D01*
X62034Y375887D01*
X62020Y375901D01*
X61992Y375942D01*
X61936Y376012D01*
X61867Y376081D01*
X61770Y376164D01*
X61659Y376248D01*
X61520Y376331D01*
X61368Y376386D01*
X61354D01*
X61285Y376414D01*
X61188Y376428D01*
X61035Y376456D01*
X60827Y376483D01*
X60591Y376497D01*
X60286Y376525D01*
D02*
G37*
G36*
X60536Y372503D02*
X58012D01*
Y369202D01*
X60744D01*
X61035Y369216D01*
X61160Y369230D01*
X61271Y369244D01*
X61285D01*
X61340Y369258D01*
X61423Y369272D01*
X61520Y369300D01*
X61756Y369383D01*
X61992Y369494D01*
X62006Y369508D01*
X62047Y369535D01*
X62103Y369577D01*
X62172Y369632D01*
X62242Y369716D01*
X62339Y369799D01*
X62408Y369910D01*
X62491Y370035D01*
X62505Y370048D01*
X62519Y370090D01*
X62547Y370173D01*
X62588Y370270D01*
X62630Y370381D01*
X62658Y370520D01*
X62671Y370686D01*
X62685Y370853D01*
Y370881D01*
Y370936D01*
X62671Y371047D01*
X62644Y371172D01*
X62616Y371311D01*
X62561Y371463D01*
X62491Y371616D01*
X62394Y371768D01*
X62380Y371782D01*
X62339Y371838D01*
X62283Y371907D01*
X62200Y371990D01*
X62089Y372087D01*
X61950Y372184D01*
X61798Y372267D01*
X61617Y372337D01*
X61590Y372351D01*
X61534Y372365D01*
X61409Y372392D01*
X61257Y372420D01*
X61063Y372448D01*
X60827Y372475D01*
X60536Y372503D01*
D02*
G37*
G36*
X42438Y371560D02*
X42424D01*
X42410Y371546D01*
X42368Y371532D01*
X42313Y371519D01*
X42243Y371491D01*
X42160Y371463D01*
X42063Y371435D01*
X41952Y371408D01*
X41827Y371366D01*
X41675Y371338D01*
X41522Y371297D01*
X41342Y371255D01*
X41148Y371213D01*
X40953Y371172D01*
X40732Y371144D01*
X40496Y371102D01*
X40468D01*
X40385Y371089D01*
X40246Y371061D01*
X40094Y371033D01*
X39927Y371005D01*
X39761Y370964D01*
X39608Y370922D01*
X39470Y370867D01*
X39456D01*
X39414Y370839D01*
X39359Y370811D01*
X39303Y370770D01*
X39137Y370659D01*
X38998Y370492D01*
Y370478D01*
X38970Y370451D01*
X38956Y370395D01*
X38929Y370326D01*
X38901Y370243D01*
X38873Y370159D01*
X38859Y370048D01*
X38846Y369938D01*
Y369924D01*
Y369854D01*
X38859Y369771D01*
X38887Y369660D01*
X38929Y369535D01*
X38998Y369411D01*
X39081Y369272D01*
X39192Y369147D01*
X39206Y369133D01*
X39262Y369105D01*
X39345Y369050D01*
X39456Y368994D01*
X39608Y368939D01*
X39789Y368884D01*
X39997Y368856D01*
X40246Y368842D01*
X40357D01*
X40496Y368856D01*
X40648Y368884D01*
X40843Y368911D01*
X41037Y368967D01*
X41245Y369036D01*
X41453Y369133D01*
X41480Y369147D01*
X41536Y369189D01*
X41633Y369258D01*
X41744Y369355D01*
X41869Y369466D01*
X42007Y369605D01*
X42119Y369771D01*
X42229Y369951D01*
X42243Y369965D01*
X42257Y370021D01*
X42285Y370118D01*
X42326Y370243D01*
X42368Y370409D01*
X42396Y370603D01*
X42410Y370839D01*
X42424Y371116D01*
X42438Y371560D01*
D02*
G37*
G36*
X13827Y376664D02*
Y376650D01*
X13813Y376622D01*
Y376567D01*
X13785Y376511D01*
X13772Y376414D01*
X13744Y376317D01*
X13688Y376081D01*
X13619Y375804D01*
X13522Y375499D01*
X13425Y375166D01*
X13300Y374819D01*
X12260Y372018D01*
X15505D01*
X14506Y374653D01*
Y374667D01*
X14493Y374708D01*
X14465Y374778D01*
X14437Y374861D01*
X14396Y374958D01*
X14354Y375083D01*
X14312Y375221D01*
X14257Y375360D01*
X14146Y375679D01*
X14035Y376012D01*
X13924Y376345D01*
X13827Y376664D01*
D02*
G37*
G36*
X90034Y374209D02*
X89951D01*
X89881Y374195D01*
X89729Y374181D01*
X89521Y374126D01*
X89285Y374043D01*
X89035Y373932D01*
X88799Y373765D01*
X88675Y373654D01*
X88564Y373543D01*
Y373530D01*
X88536Y373516D01*
X88508Y373474D01*
X88467Y373419D01*
X88425Y373349D01*
X88384Y373266D01*
X88328Y373155D01*
X88272Y373044D01*
X88217Y372905D01*
X88162Y372767D01*
X88120Y372600D01*
X88078Y372420D01*
X88037Y372226D01*
X88009Y372018D01*
X87995Y371782D01*
X87981Y371546D01*
Y371532D01*
Y371491D01*
Y371422D01*
X87995Y371324D01*
Y371213D01*
X88009Y371089D01*
X88051Y370797D01*
X88120Y370465D01*
X88231Y370132D01*
X88370Y369813D01*
X88467Y369674D01*
X88564Y369535D01*
X88578D01*
X88591Y369508D01*
X88675Y369438D01*
X88799Y369327D01*
X88966Y369216D01*
X89174Y369092D01*
X89424Y368981D01*
X89715Y368911D01*
X89867Y368897D01*
X90034Y368884D01*
X90117D01*
X90186Y368897D01*
X90339Y368925D01*
X90547Y368967D01*
X90769Y369050D01*
X91018Y369161D01*
X91254Y369327D01*
X91379Y369438D01*
X91490Y369549D01*
X91504Y369563D01*
X91518Y369577D01*
X91545Y369619D01*
X91587Y369674D01*
X91629Y369743D01*
X91684Y369827D01*
X91740Y369938D01*
X91795Y370048D01*
X91851Y370187D01*
X91892Y370340D01*
X91948Y370506D01*
X91989Y370686D01*
X92031Y370895D01*
X92059Y371102D01*
X92086Y371338D01*
Y371588D01*
Y371602D01*
Y371643D01*
Y371713D01*
X92072Y371796D01*
Y371907D01*
X92059Y372032D01*
X92017Y372323D01*
X91948Y372628D01*
X91837Y372961D01*
X91684Y373266D01*
X91601Y373419D01*
X91490Y373543D01*
Y373557D01*
X91462Y373571D01*
X91379Y373654D01*
X91254Y373751D01*
X91088Y373876D01*
X90880Y374001D01*
X90630Y374112D01*
X90353Y374181D01*
X90200Y374195D01*
X90034Y374209D01*
D02*
G37*
G36*
X82545D02*
X82323D01*
X82268Y374195D01*
X82115Y374181D01*
X81935Y374126D01*
X81713Y374056D01*
X81491Y373932D01*
X81269Y373779D01*
X81158Y373668D01*
X81047Y373557D01*
Y373543D01*
X81019Y373529D01*
X80992Y373488D01*
X80964Y373432D01*
X80922Y373377D01*
X80881Y373294D01*
X80825Y373197D01*
X80784Y373086D01*
X80728Y372961D01*
X80673Y372808D01*
X80631Y372656D01*
X80589Y372489D01*
X80562Y372295D01*
X80534Y372101D01*
X80506Y371893D01*
Y371657D01*
Y371643D01*
Y371602D01*
Y371532D01*
X80520Y371435D01*
Y371324D01*
X80534Y371186D01*
X80576Y370894D01*
X80645Y370562D01*
X80728Y370243D01*
X80867Y369924D01*
X80950Y369785D01*
X81047Y369660D01*
X81075Y369632D01*
X81144Y369563D01*
X81255Y369466D01*
X81421Y369355D01*
X81616Y369230D01*
X81851Y369133D01*
X82115Y369064D01*
X82254Y369050D01*
X82406Y369036D01*
X82489D01*
X82545Y369050D01*
X82697Y369064D01*
X82892Y369119D01*
X83100Y369189D01*
X83335Y369300D01*
X83557Y369452D01*
X83668Y369549D01*
X83779Y369660D01*
Y369674D01*
X83807Y369688D01*
X83835Y369729D01*
X83862Y369785D01*
X83904Y369841D01*
X83959Y369924D01*
X84001Y370021D01*
X84057Y370146D01*
X84112Y370270D01*
X84154Y370409D01*
X84209Y370575D01*
X84251Y370756D01*
X84278Y370936D01*
X84306Y371144D01*
X84334Y371380D01*
Y371616D01*
Y371629D01*
Y371671D01*
Y371740D01*
X84320Y371824D01*
Y371935D01*
X84306Y372059D01*
X84265Y372337D01*
X84195Y372656D01*
X84098Y372975D01*
X83959Y373294D01*
X83862Y373432D01*
X83765Y373557D01*
Y373571D01*
X83738Y373585D01*
X83668Y373654D01*
X83543Y373765D01*
X83377Y373890D01*
X83183Y374001D01*
X82947Y374112D01*
X82684Y374181D01*
X82545Y374209D01*
D02*
G37*
G36*
X78090Y403161D02*
X78076D01*
X78062Y403147D01*
X78021Y403134D01*
X77965Y403120D01*
X77896Y403092D01*
X77813Y403064D01*
X77716Y403036D01*
X77605Y403009D01*
X77480Y402967D01*
X77327Y402939D01*
X77175Y402898D01*
X76995Y402856D01*
X76800Y402814D01*
X76606Y402773D01*
X76384Y402745D01*
X76149Y402704D01*
X76121D01*
X76038Y402690D01*
X75899Y402662D01*
X75746Y402634D01*
X75580Y402607D01*
X75414Y402565D01*
X75261Y402523D01*
X75122Y402468D01*
X75108D01*
X75067Y402440D01*
X75011Y402412D01*
X74956Y402371D01*
X74790Y402260D01*
X74651Y402093D01*
Y402080D01*
X74623Y402052D01*
X74609Y401996D01*
X74581Y401927D01*
X74554Y401844D01*
X74526Y401760D01*
X74512Y401650D01*
X74498Y401539D01*
Y401525D01*
Y401455D01*
X74512Y401372D01*
X74540Y401261D01*
X74581Y401137D01*
X74651Y401012D01*
X74734Y400873D01*
X74845Y400748D01*
X74859Y400734D01*
X74914Y400706D01*
X74998Y400651D01*
X75108Y400596D01*
X75261Y400540D01*
X75441Y400485D01*
X75649Y400457D01*
X75899Y400443D01*
X76010D01*
X76149Y400457D01*
X76301Y400485D01*
X76495Y400512D01*
X76690Y400568D01*
X76898Y400637D01*
X77105Y400734D01*
X77133Y400748D01*
X77189Y400790D01*
X77286Y400859D01*
X77397Y400956D01*
X77522Y401067D01*
X77660Y401206D01*
X77771Y401372D01*
X77882Y401553D01*
X77896Y401566D01*
X77910Y401622D01*
X77938Y401719D01*
X77979Y401844D01*
X78021Y402010D01*
X78049Y402204D01*
X78062Y402440D01*
X78076Y402718D01*
X78090Y403161D01*
D02*
G37*
G36*
X32588D02*
X32574D01*
X32560Y403147D01*
X32519Y403134D01*
X32463Y403120D01*
X32394Y403092D01*
X32311Y403064D01*
X32213Y403036D01*
X32103Y403009D01*
X31978Y402967D01*
X31825Y402939D01*
X31673Y402898D01*
X31492Y402856D01*
X31298Y402814D01*
X31104Y402773D01*
X30882Y402745D01*
X30646Y402704D01*
X30619D01*
X30535Y402690D01*
X30397Y402662D01*
X30244Y402634D01*
X30078Y402607D01*
X29911Y402565D01*
X29759Y402523D01*
X29620Y402468D01*
X29606D01*
X29565Y402440D01*
X29509Y402412D01*
X29454Y402371D01*
X29287Y402260D01*
X29149Y402093D01*
Y402080D01*
X29121Y402052D01*
X29107Y401996D01*
X29079Y401927D01*
X29051Y401844D01*
X29024Y401760D01*
X29010Y401650D01*
X28996Y401539D01*
Y401525D01*
Y401455D01*
X29010Y401372D01*
X29038Y401261D01*
X29079Y401137D01*
X29149Y401012D01*
X29232Y400873D01*
X29343Y400748D01*
X29357Y400734D01*
X29412Y400706D01*
X29495Y400651D01*
X29606Y400596D01*
X29759Y400540D01*
X29939Y400485D01*
X30147Y400457D01*
X30397Y400443D01*
X30508D01*
X30646Y400457D01*
X30799Y400485D01*
X30993Y400512D01*
X31187Y400568D01*
X31395Y400637D01*
X31603Y400734D01*
X31631Y400748D01*
X31686Y400790D01*
X31784Y400859D01*
X31895Y400956D01*
X32019Y401067D01*
X32158Y401206D01*
X32269Y401372D01*
X32380Y401553D01*
X32394Y401566D01*
X32408Y401622D01*
X32435Y401719D01*
X32477Y401844D01*
X32519Y402010D01*
X32546Y402204D01*
X32560Y402440D01*
X32574Y402718D01*
X32588Y403161D01*
D02*
G37*
G36*
X95134Y405810D02*
X95051D01*
X94996Y405796D01*
X94843Y405782D01*
X94663Y405741D01*
X94441Y405672D01*
X94205Y405574D01*
X93983Y405436D01*
X93762Y405255D01*
X93734Y405228D01*
X93678Y405158D01*
X93581Y405033D01*
X93484Y404867D01*
X93373Y404673D01*
X93276Y404423D01*
X93193Y404132D01*
X93151Y403813D01*
X97048D01*
Y403827D01*
Y403855D01*
X97034Y403896D01*
Y403952D01*
X97007Y404118D01*
X96965Y404299D01*
X96896Y404520D01*
X96826Y404728D01*
X96715Y404936D01*
X96591Y405117D01*
Y405131D01*
X96563Y405145D01*
X96494Y405228D01*
X96369Y405339D01*
X96202Y405463D01*
X95994Y405588D01*
X95745Y405699D01*
X95453Y405782D01*
X95301Y405796D01*
X95134Y405810D01*
D02*
G37*
G36*
X433941Y416529D02*
X433927D01*
X433913D01*
X433830Y416515D01*
X433705Y416501D01*
X433539Y416473D01*
X433372Y416404D01*
X433178Y416320D01*
X432998Y416196D01*
X432818Y416029D01*
X432804Y416002D01*
X432748Y415932D01*
X432679Y415821D01*
X432596Y415641D01*
X432513Y415433D01*
X432443Y415155D01*
X432388Y414837D01*
X432374Y414462D01*
Y411439D01*
X435550D01*
Y414296D01*
X435536Y414462D01*
X435522Y414656D01*
X435508Y414878D01*
X435480Y415100D01*
X435439Y415322D01*
X435383Y415516D01*
X435369Y415544D01*
X435342Y415599D01*
X435300Y415682D01*
X435244Y415793D01*
X435161Y415918D01*
X435064Y416043D01*
X434939Y416168D01*
X434801Y416265D01*
X434787Y416279D01*
X434731Y416307D01*
X434648Y416348D01*
X434537Y416404D01*
X434412Y416445D01*
X434274Y416487D01*
X434107Y416515D01*
X433941Y416529D01*
D02*
G37*
G36*
X229852Y469716D02*
X225553D01*
X229852Y466693D01*
Y469716D01*
D02*
G37*
G36*
X226274Y455667D02*
X226260D01*
X226246D01*
X226163Y455653D01*
X226038Y455639D01*
X225872Y455612D01*
X225706Y455542D01*
X225511Y455459D01*
X225331Y455334D01*
X225151Y455168D01*
X225137Y455140D01*
X225081Y455071D01*
X225012Y454960D01*
X224929Y454780D01*
X224846Y454572D01*
X224776Y454294D01*
X224721Y453975D01*
X224707Y453601D01*
Y450578D01*
X227883D01*
Y453434D01*
X227869Y453601D01*
X227855Y453795D01*
X227841Y454017D01*
X227813Y454239D01*
X227772Y454461D01*
X227716Y454655D01*
X227703Y454683D01*
X227675Y454738D01*
X227633Y454821D01*
X227578Y454932D01*
X227495Y455057D01*
X227397Y455182D01*
X227273Y455307D01*
X227134Y455404D01*
X227120Y455418D01*
X227065Y455445D01*
X226981Y455487D01*
X226870Y455542D01*
X226746Y455584D01*
X226607Y455626D01*
X226441Y455653D01*
X226274Y455667D01*
D02*
G37*
G36*
X118573Y455793D02*
X115550D01*
Y452617D01*
X118407D01*
X118573Y452631D01*
X118767Y452645D01*
X118989Y452659D01*
X119211Y452687D01*
X119433Y452728D01*
X119627Y452784D01*
X119655Y452797D01*
X119710Y452825D01*
X119794Y452867D01*
X119904Y452922D01*
X120029Y453005D01*
X120154Y453102D01*
X120279Y453227D01*
X120376Y453366D01*
X120390Y453380D01*
X120418Y453435D01*
X120459Y453519D01*
X120515Y453629D01*
X120556Y453754D01*
X120598Y453893D01*
X120626Y454059D01*
X120639Y454226D01*
Y454240D01*
Y454254D01*
X120626Y454337D01*
X120612Y454462D01*
X120584Y454628D01*
X120515Y454795D01*
X120431Y454989D01*
X120307Y455169D01*
X120140Y455349D01*
X120112Y455363D01*
X120043Y455419D01*
X119932Y455488D01*
X119752Y455571D01*
X119544Y455654D01*
X119267Y455724D01*
X118947Y455779D01*
X118573Y455793D01*
D02*
G37*
G36*
X134064Y455932D02*
X133953D01*
X133828Y455904D01*
X133662Y455876D01*
X133482Y455821D01*
X133287Y455751D01*
X133107Y455640D01*
X132927Y455488D01*
X132913Y455474D01*
X132858Y455419D01*
X132788Y455322D01*
X132719Y455197D01*
X132636Y455044D01*
X132566Y454864D01*
X132511Y454670D01*
X132497Y454448D01*
Y454434D01*
Y454420D01*
X132511Y454337D01*
X132525Y454212D01*
X132552Y454059D01*
X132608Y453879D01*
X132677Y453699D01*
X132788Y453505D01*
X132927Y453338D01*
X132941Y453324D01*
X133010Y453269D01*
X133107Y453200D01*
X133232Y453130D01*
X133398Y453047D01*
X133593Y452978D01*
X133814Y452922D01*
X134064Y452908D01*
X134092D01*
X134175Y452922D01*
X134300Y452936D01*
X134466Y452964D01*
X134647Y453019D01*
X134827Y453089D01*
X135021Y453200D01*
X135187Y453338D01*
X135201Y453352D01*
X135257Y453422D01*
X135326Y453505D01*
X135409Y453629D01*
X135492Y453782D01*
X135562Y453962D01*
X135617Y454170D01*
X135631Y454392D01*
Y454406D01*
Y454420D01*
Y454503D01*
X135604Y454628D01*
X135576Y454781D01*
X135520Y454947D01*
X135437Y455127D01*
X135326Y455308D01*
X135174Y455488D01*
X135160Y455502D01*
X135090Y455557D01*
X134993Y455627D01*
X134868Y455710D01*
X134702Y455793D01*
X134522Y455862D01*
X134300Y455918D01*
X134064Y455932D01*
D02*
G37*
G36*
X134023Y451951D02*
X133939D01*
X133884Y451938D01*
X133731Y451924D01*
X133537Y451882D01*
X133315Y451813D01*
X133093Y451716D01*
X132858Y451577D01*
X132649Y451397D01*
X132622Y451369D01*
X132566Y451300D01*
X132483Y451175D01*
X132386Y451022D01*
X132275Y450814D01*
X132192Y450578D01*
X132136Y450315D01*
X132109Y450024D01*
Y449996D01*
Y449941D01*
X132122Y449843D01*
X132136Y449719D01*
X132164Y449566D01*
X132206Y449400D01*
X132261Y449233D01*
X132331Y449053D01*
X132344Y449039D01*
X132372Y448970D01*
X132428Y448887D01*
X132511Y448789D01*
X132608Y448665D01*
X132733Y448540D01*
X132871Y448429D01*
X133038Y448318D01*
X133066Y448304D01*
X133121Y448276D01*
X133218Y448235D01*
X133343Y448193D01*
X133496Y448152D01*
X133676Y448110D01*
X133870Y448082D01*
X134064Y448068D01*
X134147D01*
X134203Y448082D01*
X134369Y448096D01*
X134563Y448138D01*
X134785Y448207D01*
X135021Y448290D01*
X135243Y448429D01*
X135465Y448609D01*
X135492Y448637D01*
X135548Y448706D01*
X135645Y448831D01*
X135742Y448984D01*
X135839Y449178D01*
X135936Y449414D01*
X135992Y449691D01*
X136019Y449982D01*
Y449996D01*
Y450024D01*
Y450065D01*
X136006Y450121D01*
X135992Y450273D01*
X135950Y450481D01*
X135881Y450689D01*
X135784Y450925D01*
X135645Y451161D01*
X135451Y451383D01*
X135423Y451411D01*
X135354Y451466D01*
X135229Y451563D01*
X135063Y451674D01*
X134855Y451771D01*
X134605Y451868D01*
X134328Y451924D01*
X134023Y451951D01*
D02*
G37*
G36*
X147080Y455710D02*
X144057D01*
Y452534D01*
X146914D01*
X147080Y452548D01*
X147274Y452562D01*
X147496Y452575D01*
X147718Y452603D01*
X147940Y452645D01*
X148134Y452700D01*
X148162Y452714D01*
X148217Y452742D01*
X148301Y452784D01*
X148411Y452839D01*
X148536Y452922D01*
X148661Y453019D01*
X148786Y453144D01*
X148883Y453283D01*
X148897Y453297D01*
X148925Y453352D01*
X148966Y453435D01*
X149022Y453546D01*
X149063Y453671D01*
X149105Y453810D01*
X149133Y453976D01*
X149146Y454143D01*
Y454156D01*
Y454170D01*
X149133Y454254D01*
X149119Y454378D01*
X149091Y454545D01*
X149022Y454711D01*
X148938Y454905D01*
X148814Y455086D01*
X148647Y455266D01*
X148619Y455280D01*
X148550Y455335D01*
X148439Y455405D01*
X148259Y455488D01*
X148051Y455571D01*
X147774Y455640D01*
X147455Y455696D01*
X147080Y455710D01*
D02*
G37*
G36*
X468099Y412327D02*
X468085D01*
X468071D01*
X467988Y412313D01*
X467863Y412299D01*
X467697Y412271D01*
X467530Y412202D01*
X467336Y412119D01*
X467156Y411994D01*
X466976Y411828D01*
X466962Y411800D01*
X466906Y411731D01*
X466837Y411620D01*
X466754Y411439D01*
X466670Y411231D01*
X466601Y410954D01*
X466546Y410635D01*
X466532Y410261D01*
Y407237D01*
X469708D01*
Y410094D01*
X469694Y410261D01*
X469680Y410455D01*
X469666Y410677D01*
X469638Y410899D01*
X469597Y411120D01*
X469541Y411315D01*
X469527Y411342D01*
X469500Y411398D01*
X469458Y411481D01*
X469403Y411592D01*
X469319Y411717D01*
X469222Y411842D01*
X469097Y411966D01*
X468959Y412063D01*
X468945Y412077D01*
X468889Y412105D01*
X468806Y412147D01*
X468695Y412202D01*
X468570Y412244D01*
X468432Y412285D01*
X468265Y412313D01*
X468099Y412327D01*
D02*
G37*
G36*
X315766Y286807D02*
X315683D01*
X315627Y286793D01*
X315488Y286779D01*
X315294Y286737D01*
X315086Y286668D01*
X314850Y286557D01*
X314629Y286418D01*
X314407Y286224D01*
X314379Y286196D01*
X314323Y286127D01*
X314226Y286002D01*
X314129Y285822D01*
X314032Y285614D01*
X313935Y285350D01*
X313880Y285059D01*
X313852Y284726D01*
Y284699D01*
Y284629D01*
X313866Y284505D01*
X313880Y284352D01*
X313907Y284172D01*
X313963Y283978D01*
X314018Y283769D01*
X314102Y283561D01*
X314115Y283534D01*
X314157Y283464D01*
X314212Y283367D01*
X314296Y283242D01*
X314393Y283118D01*
X314517Y282965D01*
X314656Y282840D01*
X314823Y282715D01*
X314850Y282702D01*
X314906Y282674D01*
X315003Y282618D01*
X315128Y282577D01*
X315266Y282521D01*
X315433Y282466D01*
X315613Y282438D01*
X315807Y282424D01*
X315877D01*
X315932Y282438D01*
X316071Y282452D01*
X316251Y282494D01*
X316445Y282577D01*
X316667Y282674D01*
X316889Y282826D01*
X317000Y282910D01*
X317097Y283021D01*
Y283034D01*
X317125Y283048D01*
X317180Y283132D01*
X317264Y283270D01*
X317374Y283451D01*
X317472Y283686D01*
X317555Y283964D01*
X317610Y284283D01*
X317638Y284657D01*
Y284671D01*
Y284699D01*
Y284754D01*
X317624Y284823D01*
Y284907D01*
X317610Y285004D01*
X317569Y285226D01*
X317513Y285475D01*
X317416Y285739D01*
X317277Y285988D01*
X317097Y286224D01*
X317069Y286252D01*
X317000Y286321D01*
X316889Y286404D01*
X316737Y286515D01*
X316542Y286626D01*
X316320Y286710D01*
X316057Y286779D01*
X315766Y286807D01*
D02*
G37*
G36*
X307666Y290149D02*
X304643D01*
Y286973D01*
X307500D01*
X307666Y286987D01*
X307861Y287001D01*
X308083Y287015D01*
X308305Y287042D01*
X308526Y287084D01*
X308720Y287139D01*
X308748Y287153D01*
X308804Y287181D01*
X308887Y287223D01*
X308998Y287278D01*
X309123Y287361D01*
X309247Y287458D01*
X309372Y287583D01*
X309469Y287722D01*
X309483Y287736D01*
X309511Y287791D01*
X309553Y287875D01*
X309608Y287985D01*
X309650Y288110D01*
X309691Y288249D01*
X309719Y288415D01*
X309733Y288582D01*
Y288596D01*
Y288610D01*
X309719Y288693D01*
X309705Y288818D01*
X309678Y288984D01*
X309608Y289150D01*
X309525Y289345D01*
X309400Y289525D01*
X309234Y289705D01*
X309206Y289719D01*
X309137Y289774D01*
X309026Y289844D01*
X308845Y289927D01*
X308637Y290010D01*
X308360Y290080D01*
X308041Y290135D01*
X307666Y290149D01*
D02*
G37*
G36*
X377192Y234311D02*
X374169Y230012D01*
X377192D01*
Y234311D01*
D02*
G37*
G36*
X362311Y210013D02*
X362228D01*
X362172Y209999D01*
X362020Y209971D01*
X361839Y209929D01*
X361632Y209846D01*
X361410Y209721D01*
X361299Y209638D01*
X361188Y209555D01*
X361091Y209444D01*
X360993Y209319D01*
Y209305D01*
X360966Y209278D01*
X360938Y209222D01*
X360896Y209153D01*
X360855Y209042D01*
X360799Y208917D01*
X360758Y208764D01*
X360702Y208584D01*
X360647Y208376D01*
X360591Y208140D01*
X360536Y207877D01*
X360494Y207586D01*
X360453Y207253D01*
X360425Y206892D01*
X360411Y206504D01*
X360397Y206074D01*
Y206046D01*
Y205977D01*
Y205852D01*
X360411Y205686D01*
Y205505D01*
X360425Y205284D01*
X360439Y205048D01*
X360466Y204798D01*
X360536Y204257D01*
X360578Y203994D01*
X360633Y203744D01*
X360688Y203508D01*
X360772Y203286D01*
X360855Y203092D01*
X360952Y202926D01*
Y202912D01*
X360980Y202898D01*
X361049Y202801D01*
X361174Y202676D01*
X361326Y202537D01*
X361534Y202399D01*
X361770Y202274D01*
X362034Y202177D01*
X362172Y202163D01*
X362325Y202149D01*
X362408D01*
X362464Y202163D01*
X362602Y202191D01*
X362796Y202246D01*
X363004Y202343D01*
X363240Y202482D01*
X363351Y202565D01*
X363462Y202676D01*
X363573Y202787D01*
X363684Y202926D01*
Y202940D01*
X363712Y202967D01*
X363740Y203009D01*
X363767Y203078D01*
X363823Y203176D01*
X363864Y203300D01*
X363920Y203439D01*
X363975Y203605D01*
X364017Y203813D01*
X364072Y204035D01*
X364128Y204299D01*
X364169Y204576D01*
X364197Y204909D01*
X364225Y205256D01*
X364253Y205644D01*
Y206074D01*
Y206088D01*
Y206102D01*
Y206171D01*
Y206296D01*
X364239Y206462D01*
Y206643D01*
X364225Y206864D01*
X364211Y207100D01*
X364183Y207364D01*
X364114Y207891D01*
X364072Y208154D01*
X364017Y208404D01*
X363961Y208640D01*
X363878Y208862D01*
X363795Y209056D01*
X363698Y209222D01*
Y209236D01*
X363670Y209250D01*
X363642Y209291D01*
X363601Y209347D01*
X363476Y209472D01*
X363323Y209624D01*
X363115Y209763D01*
X362880Y209888D01*
X362755Y209943D01*
X362616Y209985D01*
X362464Y209999D01*
X362311Y210013D01*
D02*
G37*
G36*
X362471Y221814D02*
X362249D01*
X362193Y221800D01*
X362041Y221786D01*
X361860Y221731D01*
X361638Y221661D01*
X361403Y221537D01*
X361167Y221384D01*
X361056Y221273D01*
X360945Y221162D01*
Y221148D01*
X360917Y221134D01*
X360890Y221093D01*
X360862Y221051D01*
X360765Y220913D01*
X360668Y220718D01*
X360557Y220483D01*
X360460Y220191D01*
X360404Y219859D01*
X360376Y219498D01*
Y219484D01*
Y219456D01*
Y219415D01*
X360390Y219345D01*
Y219262D01*
X360404Y219179D01*
X360446Y218971D01*
X360515Y218735D01*
X360598Y218486D01*
X360737Y218236D01*
X360917Y218014D01*
X360945Y217986D01*
X361014Y217931D01*
X361139Y217834D01*
X361292Y217737D01*
X361500Y217626D01*
X361735Y217529D01*
X361999Y217473D01*
X362290Y217446D01*
X362373D01*
X362429Y217459D01*
X362581Y217473D01*
X362762Y217515D01*
X362984Y217584D01*
X363205Y217681D01*
X363427Y217820D01*
X363635Y218014D01*
X363663Y218042D01*
X363719Y218125D01*
X363802Y218250D01*
X363913Y218430D01*
X364010Y218652D01*
X364093Y218916D01*
X364149Y219235D01*
X364176Y219595D01*
Y219609D01*
Y219637D01*
Y219692D01*
X364162Y219762D01*
Y219859D01*
X364149Y219956D01*
X364107Y220177D01*
X364052Y220441D01*
X363954Y220718D01*
X363816Y220982D01*
X363635Y221218D01*
Y221231D01*
X363608Y221245D01*
X363538Y221315D01*
X363427Y221412D01*
X363275Y221523D01*
X363081Y221620D01*
X362859Y221717D01*
X362609Y221786D01*
X362471Y221814D01*
D02*
G37*
G36*
X491554Y435741D02*
X488530D01*
Y432565D01*
X491387D01*
X491554Y432579D01*
X491748Y432593D01*
X491970Y432607D01*
X492192Y432635D01*
X492413Y432676D01*
X492608Y432732D01*
X492635Y432745D01*
X492691Y432773D01*
X492774Y432815D01*
X492885Y432870D01*
X493010Y432953D01*
X493135Y433050D01*
X493260Y433175D01*
X493357Y433314D01*
X493371Y433328D01*
X493398Y433383D01*
X493440Y433467D01*
X493495Y433577D01*
X493537Y433702D01*
X493578Y433841D01*
X493606Y434007D01*
X493620Y434174D01*
Y434188D01*
Y434202D01*
X493606Y434285D01*
X493592Y434410D01*
X493565Y434576D01*
X493495Y434743D01*
X493412Y434937D01*
X493287Y435117D01*
X493121Y435297D01*
X493093Y435311D01*
X493024Y435367D01*
X492913Y435436D01*
X492733Y435519D01*
X492524Y435602D01*
X492247Y435672D01*
X491928Y435727D01*
X491554Y435741D01*
D02*
G37*
G36*
X499584Y435880D02*
X499473D01*
X499348Y435852D01*
X499181Y435824D01*
X499001Y435769D01*
X498807Y435699D01*
X498627Y435588D01*
X498446Y435436D01*
X498432Y435422D01*
X498377Y435367D01*
X498308Y435270D01*
X498238Y435145D01*
X498155Y434992D01*
X498086Y434812D01*
X498030Y434618D01*
X498016Y434396D01*
Y434382D01*
Y434368D01*
X498030Y434285D01*
X498044Y434160D01*
X498072Y434007D01*
X498127Y433827D01*
X498197Y433647D01*
X498308Y433453D01*
X498446Y433286D01*
X498460Y433272D01*
X498530Y433217D01*
X498627Y433148D01*
X498751Y433078D01*
X498918Y432995D01*
X499112Y432926D01*
X499334Y432870D01*
X499584Y432856D01*
X499611D01*
X499695Y432870D01*
X499819Y432884D01*
X499986Y432912D01*
X500166Y432967D01*
X500346Y433037D01*
X500540Y433148D01*
X500707Y433286D01*
X500721Y433300D01*
X500776Y433369D01*
X500845Y433453D01*
X500929Y433577D01*
X501012Y433730D01*
X501081Y433910D01*
X501137Y434118D01*
X501151Y434340D01*
Y434354D01*
Y434368D01*
Y434451D01*
X501123Y434576D01*
X501095Y434729D01*
X501040Y434895D01*
X500956Y435075D01*
X500845Y435256D01*
X500693Y435436D01*
X500679Y435450D01*
X500610Y435505D01*
X500513Y435575D01*
X500388Y435658D01*
X500221Y435741D01*
X500041Y435810D01*
X499819Y435866D01*
X499584Y435880D01*
D02*
G37*
G36*
X499542Y431899D02*
X499459D01*
X499403Y431886D01*
X499251Y431872D01*
X499057Y431830D01*
X498835Y431761D01*
X498613Y431664D01*
X498377Y431525D01*
X498169Y431345D01*
X498141Y431317D01*
X498086Y431248D01*
X498003Y431123D01*
X497905Y430970D01*
X497794Y430762D01*
X497711Y430527D01*
X497656Y430263D01*
X497628Y429972D01*
Y429944D01*
Y429888D01*
X497642Y429791D01*
X497656Y429667D01*
X497683Y429514D01*
X497725Y429348D01*
X497781Y429181D01*
X497850Y429001D01*
X497864Y428987D01*
X497892Y428918D01*
X497947Y428834D01*
X498030Y428737D01*
X498127Y428613D01*
X498252Y428488D01*
X498391Y428377D01*
X498557Y428266D01*
X498585Y428252D01*
X498641Y428224D01*
X498737Y428183D01*
X498862Y428141D01*
X499015Y428100D01*
X499195Y428058D01*
X499389Y428030D01*
X499584Y428016D01*
X499667D01*
X499722Y428030D01*
X499889Y428044D01*
X500083Y428086D01*
X500305Y428155D01*
X500540Y428238D01*
X500762Y428377D01*
X500984Y428557D01*
X501012Y428585D01*
X501067Y428654D01*
X501165Y428779D01*
X501262Y428932D01*
X501359Y429126D01*
X501456Y429361D01*
X501511Y429639D01*
X501539Y429930D01*
Y429944D01*
Y429972D01*
Y430013D01*
X501525Y430069D01*
X501511Y430221D01*
X501470Y430429D01*
X501400Y430637D01*
X501303Y430873D01*
X501165Y431109D01*
X500970Y431331D01*
X500943Y431359D01*
X500873Y431414D01*
X500748Y431511D01*
X500582Y431622D01*
X500374Y431719D01*
X500124Y431816D01*
X499847Y431872D01*
X499542Y431899D01*
D02*
G37*
G36*
X126857Y73425D02*
X126843D01*
X126830D01*
X126746Y73412D01*
X126622Y73398D01*
X126455Y73370D01*
X126289Y73301D01*
X126095Y73218D01*
X125914Y73093D01*
X125734Y72926D01*
X125720Y72899D01*
X125665Y72829D01*
X125595Y72718D01*
X125512Y72538D01*
X125429Y72330D01*
X125359Y72053D01*
X125304Y71734D01*
X125290Y71359D01*
Y68336D01*
X128466D01*
Y71193D01*
X128452Y71359D01*
X128438Y71553D01*
X128424Y71775D01*
X128397Y71997D01*
X128355Y72219D01*
X128300Y72413D01*
X128286Y72441D01*
X128258Y72496D01*
X128216Y72580D01*
X128161Y72691D01*
X128078Y72815D01*
X127981Y72940D01*
X127856Y73065D01*
X127717Y73162D01*
X127703Y73176D01*
X127648Y73204D01*
X127565Y73245D01*
X127454Y73301D01*
X127329Y73342D01*
X127190Y73384D01*
X127024Y73412D01*
X126857Y73425D01*
D02*
G37*
G36*
X55085Y153138D02*
X55001D01*
X54946Y153125D01*
X54807Y153111D01*
X54613Y153069D01*
X54405Y153000D01*
X54169Y152889D01*
X53947Y152750D01*
X53725Y152556D01*
X53698Y152528D01*
X53642Y152459D01*
X53545Y152334D01*
X53448Y152154D01*
X53351Y151946D01*
X53254Y151682D01*
X53198Y151391D01*
X53171Y151058D01*
Y151030D01*
Y150961D01*
X53185Y150836D01*
X53198Y150684D01*
X53226Y150503D01*
X53282Y150309D01*
X53337Y150101D01*
X53420Y149893D01*
X53434Y149865D01*
X53476Y149796D01*
X53531Y149699D01*
X53615Y149574D01*
X53712Y149449D01*
X53836Y149297D01*
X53975Y149172D01*
X54142Y149047D01*
X54169Y149033D01*
X54225Y149005D01*
X54322Y148950D01*
X54447Y148909D01*
X54585Y148853D01*
X54752Y148798D01*
X54932Y148770D01*
X55126Y148756D01*
X55195D01*
X55251Y148770D01*
X55390Y148784D01*
X55570Y148825D01*
X55764Y148909D01*
X55986Y149005D01*
X56208Y149158D01*
X56319Y149241D01*
X56416Y149352D01*
Y149366D01*
X56444Y149380D01*
X56499Y149463D01*
X56582Y149602D01*
X56693Y149782D01*
X56790Y150018D01*
X56874Y150295D01*
X56929Y150614D01*
X56957Y150989D01*
Y151003D01*
Y151030D01*
Y151086D01*
X56943Y151155D01*
Y151238D01*
X56929Y151335D01*
X56887Y151557D01*
X56832Y151807D01*
X56735Y152071D01*
X56596Y152320D01*
X56416Y152556D01*
X56388Y152584D01*
X56319Y152653D01*
X56208Y152736D01*
X56055Y152847D01*
X55861Y152958D01*
X55639Y153041D01*
X55376Y153111D01*
X55085Y153138D01*
D02*
G37*
G36*
X243471Y199141D02*
X240448Y194841D01*
X243471D01*
Y199141D01*
D02*
G37*
G36*
X234817Y199986D02*
X231794D01*
Y196811D01*
X234651D01*
X234817Y196824D01*
X235011Y196838D01*
X235233Y196852D01*
X235455Y196880D01*
X235677Y196922D01*
X235871Y196977D01*
X235899Y196991D01*
X235954Y197019D01*
X236037Y197060D01*
X236148Y197116D01*
X236273Y197199D01*
X236398Y197296D01*
X236523Y197421D01*
X236620Y197560D01*
X236634Y197573D01*
X236661Y197629D01*
X236703Y197712D01*
X236759Y197823D01*
X236800Y197948D01*
X236842Y198087D01*
X236870Y198253D01*
X236883Y198419D01*
Y198433D01*
Y198447D01*
X236870Y198530D01*
X236856Y198655D01*
X236828Y198822D01*
X236759Y198988D01*
X236675Y199182D01*
X236551Y199363D01*
X236384Y199543D01*
X236356Y199557D01*
X236287Y199612D01*
X236176Y199681D01*
X235996Y199765D01*
X235788Y199848D01*
X235510Y199917D01*
X235191Y199973D01*
X234817Y199986D01*
D02*
G37*
G36*
X225005Y351801D02*
X224922D01*
X224867Y351788D01*
X224714Y351760D01*
X224534Y351718D01*
X224326Y351635D01*
X224104Y351510D01*
X223993Y351427D01*
X223882Y351344D01*
X223785Y351233D01*
X223688Y351108D01*
Y351094D01*
X223660Y351067D01*
X223632Y351011D01*
X223591Y350942D01*
X223549Y350831D01*
X223494Y350706D01*
X223452Y350553D01*
X223396Y350373D01*
X223341Y350165D01*
X223286Y349929D01*
X223230Y349666D01*
X223188Y349375D01*
X223147Y349042D01*
X223119Y348681D01*
X223105Y348293D01*
X223091Y347863D01*
Y347835D01*
Y347766D01*
Y347641D01*
X223105Y347475D01*
Y347294D01*
X223119Y347072D01*
X223133Y346837D01*
X223161Y346587D01*
X223230Y346046D01*
X223272Y345783D01*
X223327Y345533D01*
X223383Y345297D01*
X223466Y345075D01*
X223549Y344881D01*
X223646Y344715D01*
Y344701D01*
X223674Y344687D01*
X223743Y344590D01*
X223868Y344465D01*
X224021Y344326D01*
X224229Y344188D01*
X224464Y344063D01*
X224728Y343966D01*
X224867Y343952D01*
X225019Y343938D01*
X225102D01*
X225158Y343952D01*
X225296Y343980D01*
X225491Y344035D01*
X225699Y344132D01*
X225934Y344271D01*
X226045Y344354D01*
X226156Y344465D01*
X226267Y344576D01*
X226378Y344715D01*
Y344729D01*
X226406Y344756D01*
X226434Y344798D01*
X226461Y344867D01*
X226517Y344964D01*
X226558Y345089D01*
X226614Y345228D01*
X226669Y345394D01*
X226711Y345602D01*
X226766Y345824D01*
X226822Y346088D01*
X226864Y346365D01*
X226891Y346698D01*
X226919Y347045D01*
X226947Y347433D01*
Y347863D01*
Y347877D01*
Y347891D01*
Y347960D01*
Y348085D01*
X226933Y348251D01*
Y348432D01*
X226919Y348653D01*
X226905Y348889D01*
X226877Y349153D01*
X226808Y349680D01*
X226766Y349943D01*
X226711Y350193D01*
X226656Y350429D01*
X226572Y350650D01*
X226489Y350845D01*
X226392Y351011D01*
Y351025D01*
X226364Y351039D01*
X226337Y351080D01*
X226295Y351136D01*
X226170Y351261D01*
X226018Y351413D01*
X225810Y351552D01*
X225574Y351677D01*
X225449Y351732D01*
X225310Y351774D01*
X225158Y351788D01*
X225005Y351801D01*
D02*
G37*
G36*
X218430Y339733D02*
X218208D01*
X218153Y339719D01*
X218000Y339705D01*
X217820Y339650D01*
X217598Y339580D01*
X217362Y339455D01*
X217127Y339303D01*
X217016Y339192D01*
X216905Y339081D01*
Y339067D01*
X216877Y339053D01*
X216849Y339012D01*
X216821Y338970D01*
X216724Y338831D01*
X216627Y338637D01*
X216516Y338401D01*
X216419Y338110D01*
X216364Y337777D01*
X216336Y337417D01*
Y337403D01*
Y337375D01*
Y337334D01*
X216350Y337264D01*
Y337181D01*
X216364Y337098D01*
X216406Y336890D01*
X216475Y336654D01*
X216558Y336404D01*
X216697Y336155D01*
X216877Y335933D01*
X216905Y335905D01*
X216974Y335850D01*
X217099Y335753D01*
X217251Y335656D01*
X217460Y335545D01*
X217695Y335448D01*
X217959Y335392D01*
X218250Y335364D01*
X218333D01*
X218389Y335378D01*
X218541Y335392D01*
X218722Y335434D01*
X218943Y335503D01*
X219165Y335600D01*
X219387Y335739D01*
X219595Y335933D01*
X219623Y335961D01*
X219678Y336044D01*
X219762Y336169D01*
X219873Y336349D01*
X219970Y336571D01*
X220053Y336834D01*
X220108Y337153D01*
X220136Y337514D01*
Y337528D01*
Y337556D01*
Y337611D01*
X220122Y337680D01*
Y337777D01*
X220108Y337874D01*
X220067Y338096D01*
X220011Y338360D01*
X219914Y338637D01*
X219776Y338901D01*
X219595Y339137D01*
Y339150D01*
X219568Y339164D01*
X219498Y339234D01*
X219387Y339331D01*
X219235Y339442D01*
X219041Y339539D01*
X218819Y339636D01*
X218569Y339705D01*
X218430Y339733D01*
D02*
G37*
G36*
X12102Y118806D02*
X12088D01*
X12074D01*
X11991Y118792D01*
X11866Y118778D01*
X11700Y118751D01*
X11533Y118681D01*
X11339Y118598D01*
X11159Y118473D01*
X10979Y118307D01*
X10965Y118279D01*
X10909Y118210D01*
X10840Y118099D01*
X10757Y117919D01*
X10674Y117711D01*
X10604Y117433D01*
X10549Y117114D01*
X10535Y116740D01*
Y113716D01*
X13711D01*
Y116573D01*
X13697Y116740D01*
X13683Y116934D01*
X13669Y117156D01*
X13641Y117378D01*
X13600Y117600D01*
X13544Y117794D01*
X13530Y117822D01*
X13503Y117877D01*
X13461Y117960D01*
X13406Y118071D01*
X13322Y118196D01*
X13225Y118321D01*
X13101Y118446D01*
X12962Y118543D01*
X12948Y118557D01*
X12892Y118584D01*
X12809Y118626D01*
X12698Y118681D01*
X12573Y118723D01*
X12435Y118765D01*
X12268Y118792D01*
X12102Y118806D01*
D02*
G37*
G36*
X90065Y192182D02*
X89844D01*
X89788Y192168D01*
X89635Y192154D01*
X89455Y192099D01*
X89233Y192029D01*
X88998Y191904D01*
X88762Y191752D01*
X88651Y191641D01*
X88540Y191530D01*
Y191516D01*
X88512Y191502D01*
X88484Y191460D01*
X88457Y191419D01*
X88360Y191280D01*
X88263Y191086D01*
X88152Y190850D01*
X88055Y190559D01*
X87999Y190226D01*
X87971Y189866D01*
Y189852D01*
Y189824D01*
Y189782D01*
X87985Y189713D01*
Y189630D01*
X87999Y189547D01*
X88041Y189339D01*
X88110Y189103D01*
X88193Y188853D01*
X88332Y188604D01*
X88512Y188382D01*
X88540Y188354D01*
X88609Y188298D01*
X88734Y188202D01*
X88887Y188104D01*
X89095Y187993D01*
X89330Y187896D01*
X89594Y187841D01*
X89885Y187813D01*
X89968D01*
X90024Y187827D01*
X90176Y187841D01*
X90357Y187882D01*
X90579Y187952D01*
X90801Y188049D01*
X91022Y188188D01*
X91230Y188382D01*
X91258Y188410D01*
X91314Y188493D01*
X91397Y188617D01*
X91508Y188798D01*
X91605Y189020D01*
X91688Y189283D01*
X91743Y189602D01*
X91771Y189963D01*
Y189977D01*
Y190004D01*
Y190060D01*
X91757Y190129D01*
Y190226D01*
X91743Y190323D01*
X91702Y190545D01*
X91646Y190809D01*
X91549Y191086D01*
X91411Y191350D01*
X91230Y191585D01*
Y191599D01*
X91203Y191613D01*
X91133Y191682D01*
X91022Y191779D01*
X90870Y191890D01*
X90676Y191987D01*
X90454Y192085D01*
X90204Y192154D01*
X90065Y192182D01*
D02*
G37*
G36*
X82327Y191974D02*
X79581D01*
Y188548D01*
X82160D01*
X82257Y188562D01*
X82355D01*
X82465Y188576D01*
X82729Y188604D01*
X83020Y188659D01*
X83312Y188742D01*
X83575Y188853D01*
X83700Y188923D01*
X83797Y189006D01*
X83825Y189034D01*
X83880Y189089D01*
X83963Y189200D01*
X84060Y189339D01*
X84157Y189519D01*
X84241Y189741D01*
X84296Y189991D01*
X84324Y190282D01*
Y190296D01*
Y190309D01*
Y190379D01*
X84310Y190504D01*
X84282Y190642D01*
X84255Y190795D01*
X84199Y190975D01*
X84116Y191142D01*
X84019Y191308D01*
X84005Y191322D01*
X83963Y191377D01*
X83894Y191447D01*
X83811Y191544D01*
X83686Y191641D01*
X83547Y191724D01*
X83395Y191807D01*
X83214Y191877D01*
X83201D01*
X83145Y191890D01*
X83062Y191904D01*
X82951Y191932D01*
X82785Y191946D01*
X82577Y191960D01*
X82327Y191974D01*
D02*
G37*
G36*
X194122Y22929D02*
X189823D01*
X194122Y19906D01*
Y22929D01*
D02*
G37*
%LPD*%
D10*
X231943Y120239D02*
G03*
X231943Y120239I-1250J0D01*
G01*
D11*
X215000Y207811D02*
G03*
X215000Y207811I-1500J0D01*
G01*
D12*
X432447Y206471D02*
G03*
X432447Y206471I-2500J0D01*
G01*
X357750Y231250D02*
G03*
X357750Y231250I-2500J0D01*
G01*
X284000Y407250D02*
G03*
X284000Y407250I-2500J0D01*
G01*
D13*
X261693Y32089D02*
X293193D01*
X261693D02*
Y136089D01*
X293193D01*
X154000Y65500D02*
Y80000D01*
X137000Y65500D02*
Y80000D01*
D14*
X352500Y425300D02*
X365000D01*
X352500Y477300D02*
X365000D01*
X295000D02*
X307500D01*
X295000Y425300D02*
X307500D01*
X196500Y279811D02*
Y287811D01*
X204000D01*
X290500Y213811D02*
X290500Y221811D01*
X283500Y213811D02*
X290500D01*
Y279811D02*
Y287811D01*
X283500D02*
X290500D01*
X196500Y213811D02*
Y221811D01*
Y213811D02*
X204000D01*
X47250Y113250D02*
Y125250D01*
X21250Y113250D02*
Y125250D01*
X344612Y406471D02*
X411947D01*
X157947D02*
X249546D01*
X157947Y184471D02*
X411947D01*
X296250Y310397D02*
X296250Y339250D01*
X296250Y239250D02*
X296250Y289516D01*
X374250Y339250D02*
X374250Y239250D01*
X296250Y339250D02*
X374250Y339250D01*
X296250Y239250D02*
X374250Y239250D01*
X260000Y399249D02*
X338000Y399249D01*
X338000Y299249D01*
X260000Y399249D02*
X260000Y299249D01*
X283320Y299249D01*
X307648Y299249D02*
X338000Y299249D01*
X61000Y105850D02*
X83000D01*
X98500D02*
X120500Y105850D01*
X133750Y107250D02*
X155750D01*
D15*
X19950Y165000D02*
Y193000D01*
Y165000D02*
X73950D01*
Y193000D01*
X19950D02*
X73950D01*
M02*
